FILE_TYPE = MACRO_DRAWING;
SET COLOR_WIRE YELLOW;
SET COLOR_PROP MONO;
SET COLOR_DOT WHITE;
SET COLOR_ARC YELLOW;
SET COLOR_BODY GREEN;
SET COLOR_NOTE MONO;
SET PROP_DISPLAY VALUE;
SET PAGE_NUMBER P89;
FORCEADD RES..1
(-2250 3025);
FORCEPROP 1 LAST TOLERANCE 5%
J 0
(-2250 2925);
DISPLAY 0.617021 (-2250 2925);
PAINT SKYBLUE (-2250 2925);
FORCEPROP 1 LAST VALUE 0.0
J 2
(-2275 2925);
DISPLAY 0.617021 (-2275 2925);
PAINT SKYBLUE (-2275 2925);
FORCEPROP 1 LASTPIN (-2350 3025) $PN 1
J 0
(-2338 3037);
DISPLAY 0.617021 (-2338 3037);
PAINT ORANGE (-2338 3037);
FORCEPROP 1 LAST LOCATION R4T2
J 0
(-2300 3075);
DISPLAY 0.617021 (-2300 3075);
PAINT AQUA (-2300 3075);
FORCEPROP 1 LASTPIN (-2150 3025) $PN 2
J 0
(-2188 3037);
DISPLAY 0.617021 (-2188 3037);
PAINT ORANGE (-2188 3037);
FORCEPROP 1 LAST PART_NUMBER G21497-005
J 0
(-2300 3125);
DISPLAY 0.617021 (-2300 3125);
PAINT BLUE (-2300 3125);
FORCEPROP 1 LAST WATTAGE 1/16W
J 2
(-2275 2875);
DISPLAY 0.617021 (-2275 2875);
PAINT SKYBLUE (-2275 2875);
FORCEPROP 1 LAST PACK_TYPE 0402
J 0
(-2100 2875);
DISPLAY 0.617021 (-2100 2875);
PAINT SKYBLUE (-2100 2875);
FORCEPROP 1 LAST MATERIAL EMPTY
J 0
(-2250 2875);
DISPLAY 0.617021 (-2250 2875);
PAINT RED (-2250 2875);
FORCEPROP 2 LAST CDS_LOCATION R4T2
J 0
(-2300 3075);
DISPLAY 0.617021 (-2300 3075);
PAINT AQUA (-2300 3075);
DISPLAY INVISIBLE (-2300 3075);
FORCEPROP 2 LAST CDS_LIB mstr_discrete
J 0
(-2250 3025);
PAINT ORANGE (-2250 3025);
DISPLAY INVISIBLE (-2250 3025);
FORCEPROP 1 LAST PATH I1
J 0
(-2300 3175);
DISPLAY 0.978723 (-2300 3175);
PAINT WHITE (-2300 3175);
DISPLAY INVISIBLE (-2300 3175);
FORCEPROP 0 LAST SEC 1
J 0
(-2300 3175);
DISPLAY 0.680851 (-2300 3175);
PAINT MONO (-2300 3175);
DISPLAY INVISIBLE (-2300 3175);
FORCEPROP 0 LAST ROOM NV_DIMM
J 0
(-2300 3225);
DISPLAY 1.021277 (-2300 3225);
PAINT ORANGE (-2300 3225);
DISPLAY INVISIBLE (-2300 3225);
FORCEPROP 2 LAST SEC_TYPE 0402
J 0
(-2300 3225);
DISPLAY 1.021277 (-2300 3225);
PAINT ORANGE (-2300 3225);
DISPLAY INVISIBLE (-2300 3225);
FORCEPROP 0 LAST BOM_COST MEM_NV
J 0
(-2300 3325);
DISPLAY 1.021277 (-2300 3325);
PAINT ORANGE (-2300 3325);
DISPLAY INVISIBLE (-2300 3325);
FORCEADD OFFPAGE..1
(-2875 2725);
FORCEPROP 2 LASTPIN (-2825 2725) SIG_NAME FM_ADR_COMPLETE_DLY
J 0
(-2835 2735);
DISPLAY 0.617021 (-2835 2735);
PAINT ORANGE (-2835 2735);
FORCEPROP 2 LAST $XR0 191 
J 0
(-3127 2725);
DISPLAY 0.638298 (-3127 2725);
PAINT MONO (-3127 2725);
FORCEPROP 2 LAST PATH I10
J 0
(-2825 2800);
DISPLAY 1.021277 (-2825 2800);
PAINT ORANGE (-2825 2800);
DISPLAY INVISIBLE (-2825 2800);
FORCEPROP 2 LAST CDS_LIB mstr_standard
J 0
(-2875 2725);
PAINT ORANGE (-2875 2725);
DISPLAY INVISIBLE (-2875 2725);
FORCEPROP 1 LAST OFFPAGE TRUE
J 0
(-2550 2600);
DISPLAY 0.872340 (-2550 2600);
PAINT GREEN (-2550 2600);
DISPLAY INVISIBLE (-2550 2600);
FORCEPROP 1 LAST COMMENT_BODY TRUE
J 0
(-2750 2625);
DISPLAY 0.872340 (-2750 2625);
PAINT GREEN (-2750 2625);
DISPLAY INVISIBLE (-2750 2625);
FORCEADD OFFPAGE..2
(1400 3125);
FORCEPROP 2 LASTPIN (1350 3125) SIG_NAME FM_ADR_COMPLETE_ABC_N
J 2
(1340 3135);
DISPLAY 0.617021 (1340 3135);
PAINT ORANGE (1340 3135);
FORCEPROP 2 LAST $XR5 48 
J 0
(2039 3125);
DISPLAY 0.638298 (2039 3125);
PAINT MONO (2039 3125);
FORCEPROP 2 LAST $XR4 47 
J 0
(1949 3125);
DISPLAY 0.638298 (1949 3125);
PAINT MONO (1949 3125);
FORCEPROP 2 LAST $XR3 46 
J 0
(1859 3125);
DISPLAY 0.638298 (1859 3125);
PAINT MONO (1859 3125);
FORCEPROP 2 LAST $XR2 45 
J 0
(1769 3125);
DISPLAY 0.638298 (1769 3125);
PAINT MONO (1769 3125);
FORCEPROP 2 LAST $XR1 44 
J 0
(1679 3125);
DISPLAY 0.638298 (1679 3125);
PAINT MONO (1679 3125);
FORCEPROP 2 LAST $XR0 43 
J 0
(1589 3125);
DISPLAY 0.638298 (1589 3125);
PAINT MONO (1589 3125);
FORCEPROP 2 LAST PATH I11
J 0
(1575 3200);
DISPLAY 1.021277 (1575 3200);
PAINT ORANGE (1575 3200);
DISPLAY INVISIBLE (1575 3200);
FORCEPROP 2 LAST CDS_LIB mstr_standard
J 0
(1400 3125);
PAINT ORANGE (1400 3125);
DISPLAY INVISIBLE (1400 3125);
FORCEPROP 1 LAST OFFPAGE TRUE
J 0
(1725 3000);
DISPLAY 0.872340 (1725 3000);
PAINT GREEN (1725 3000);
DISPLAY INVISIBLE (1725 3000);
FORCEPROP 1 LAST COMMENT_BODY TRUE
J 0
(1355 3030);
DISPLAY 0.872340 (1355 3030);
PAINT GREEN (1355 3030);
DISPLAY INVISIBLE (1355 3030);
FORCEADD OFFPAGE..2
(1400 2825);
FORCEPROP 2 LASTPIN (1350 2825) SIG_NAME FM_ADR_COMPLETE_DEF_N
J 2
(1325 2835);
DISPLAY 0.617021 (1325 2835);
PAINT ORANGE (1325 2835);
FORCEPROP 2 LAST $XR5 54 
J 0
(2039 2825);
DISPLAY 0.638298 (2039 2825);
PAINT MONO (2039 2825);
FORCEPROP 2 LAST $XR4 53 
J 0
(1949 2825);
DISPLAY 0.638298 (1949 2825);
PAINT MONO (1949 2825);
FORCEPROP 2 LAST $XR3 52 
J 0
(1859 2825);
DISPLAY 0.638298 (1859 2825);
PAINT MONO (1859 2825);
FORCEPROP 2 LAST $XR2 51 
J 0
(1769 2825);
DISPLAY 0.638298 (1769 2825);
PAINT MONO (1769 2825);
FORCEPROP 2 LAST $XR1 50 
J 0
(1679 2825);
DISPLAY 0.638298 (1679 2825);
PAINT MONO (1679 2825);
FORCEPROP 2 LAST $XR0 49 
J 0
(1589 2825);
DISPLAY 0.638298 (1589 2825);
PAINT MONO (1589 2825);
FORCEPROP 2 LAST PATH I12
J 0
(1575 2900);
DISPLAY 1.021277 (1575 2900);
PAINT ORANGE (1575 2900);
DISPLAY INVISIBLE (1575 2900);
FORCEPROP 2 LAST CDS_LIB mstr_standard
J 0
(1400 2825);
PAINT ORANGE (1400 2825);
DISPLAY INVISIBLE (1400 2825);
FORCEPROP 1 LAST OFFPAGE TRUE
J 0
(1725 2700);
DISPLAY 0.872340 (1725 2700);
PAINT GREEN (1725 2700);
DISPLAY INVISIBLE (1725 2700);
FORCEPROP 1 LAST COMMENT_BODY TRUE
J 0
(1355 2730);
DISPLAY 0.872340 (1355 2730);
PAINT GREEN (1355 2730);
DISPLAY INVISIBLE (1355 2730);
FORCEADD OFFPAGE..2
(1400 1950);
FORCEPROP 2 LASTPIN (1350 1950) SIG_NAME FM_ADR_COMPLETE_GHJ_N
J 2
(1325 1960);
DISPLAY 0.617021 (1325 1960);
PAINT ORANGE (1325 1960);
FORCEPROP 2 LAST $XR5 82 
J 0
(2039 1950);
DISPLAY 0.638298 (2039 1950);
PAINT MONO (2039 1950);
FORCEPROP 2 LAST $XR4 81 
J 0
(1949 1950);
DISPLAY 0.638298 (1949 1950);
PAINT MONO (1949 1950);
FORCEPROP 2 LAST $XR3 80 
J 0
(1859 1950);
DISPLAY 0.638298 (1859 1950);
PAINT MONO (1859 1950);
FORCEPROP 2 LAST $XR2 79 
J 0
(1769 1950);
DISPLAY 0.638298 (1769 1950);
PAINT MONO (1769 1950);
FORCEPROP 2 LAST $XR1 78 
J 0
(1679 1950);
DISPLAY 0.638298 (1679 1950);
PAINT MONO (1679 1950);
FORCEPROP 2 LAST $XR0 77 
J 0
(1589 1950);
DISPLAY 0.638298 (1589 1950);
PAINT MONO (1589 1950);
FORCEPROP 2 LAST CDS_LIB mstr_standard
J 0
(1400 1950);
PAINT ORANGE (1400 1950);
DISPLAY INVISIBLE (1400 1950);
FORCEPROP 2 LAST PATH I13
J 0
(1575 2025);
DISPLAY 1.021277 (1575 2025);
PAINT ORANGE (1575 2025);
DISPLAY INVISIBLE (1575 2025);
FORCEPROP 1 LAST OFFPAGE TRUE
J 0
(1725 1825);
DISPLAY 0.872340 (1725 1825);
PAINT GREEN (1725 1825);
DISPLAY INVISIBLE (1725 1825);
FORCEPROP 1 LAST COMMENT_BODY TRUE
J 0
(1355 1855);
DISPLAY 0.872340 (1355 1855);
PAINT GREEN (1355 1855);
DISPLAY INVISIBLE (1355 1855);
FORCEADD OFFPAGE..2
(1400 1650);
FORCEPROP 2 LASTPIN (1350 1650) SIG_NAME FM_ADR_COMPLETE_KLM_N
J 2
(1325 1660);
DISPLAY 0.617021 (1325 1660);
PAINT ORANGE (1325 1660);
FORCEPROP 2 LAST $XR5 88 
J 0
(2039 1650);
DISPLAY 0.638298 (2039 1650);
PAINT MONO (2039 1650);
FORCEPROP 2 LAST $XR4 87 
J 0
(1949 1650);
DISPLAY 0.638298 (1949 1650);
PAINT MONO (1949 1650);
FORCEPROP 2 LAST $XR3 86 
J 0
(1859 1650);
DISPLAY 0.638298 (1859 1650);
PAINT MONO (1859 1650);
FORCEPROP 2 LAST $XR2 85 
J 0
(1769 1650);
DISPLAY 0.638298 (1769 1650);
PAINT MONO (1769 1650);
FORCEPROP 2 LAST $XR1 84 
J 0
(1679 1650);
DISPLAY 0.638298 (1679 1650);
PAINT MONO (1679 1650);
FORCEPROP 2 LAST $XR0 83 
J 0
(1589 1650);
DISPLAY 0.638298 (1589 1650);
PAINT MONO (1589 1650);
FORCEPROP 2 LAST CDS_LIB mstr_standard
J 0
(1400 1650);
PAINT ORANGE (1400 1650);
DISPLAY INVISIBLE (1400 1650);
FORCEPROP 2 LAST PATH I14
J 0
(1575 1725);
DISPLAY 1.021277 (1575 1725);
PAINT ORANGE (1575 1725);
DISPLAY INVISIBLE (1575 1725);
FORCEPROP 1 LAST OFFPAGE TRUE
J 0
(1725 1525);
DISPLAY 0.872340 (1725 1525);
PAINT GREEN (1725 1525);
DISPLAY INVISIBLE (1725 1525);
FORCEPROP 1 LAST COMMENT_BODY TRUE
J 0
(1355 1555);
DISPLAY 0.872340 (1355 1555);
PAINT GREEN (1355 1555);
DISPLAY INVISIBLE (1355 1555);
FORCEADD GND..1
(-450 2525);
FORCEPROP 3 LASTPIN (-450 2575) SIG_NAME GND\g
J 0
(-440 2585);
DISPLAY 0.659574 (-440 2585);
PAINT MONO (-440 2585);
DISPLAY INVISIBLE (-440 2585);
FORCEPROP 1 LAST SIZE 1B
J 0
(-375 2475);
DISPLAY 0.872340 (-375 2475);
PAINT AQUA (-375 2475);
DISPLAY INVISIBLE (-375 2475);
FORCEPROP 2 LAST CDS_LIB mstr_symbols
J 0
(-450 2525);
PAINT ORANGE (-450 2525);
DISPLAY INVISIBLE (-450 2525);
FORCEPROP 1 LAST VOLTAGE 0.0V
J 0
(-495 2482);
DISPLAY 0.340426 (-495 2482);
PAINT SKYBLUE (-495 2482);
DISPLAY INVISIBLE (-495 2482);
FORCEPROP 1 LAST PATH I16
J 0
(-375 2525);
DISPLAY 0.872340 (-375 2525);
PAINT AQUA (-375 2525);
DISPLAY INVISIBLE (-375 2525);
FORCEPROP 1 LAST BODY_TYPE PLUMBING
J 0
(-495 2482);
DISPLAY 0.340426 (-495 2482);
PAINT GREEN (-495 2482);
DISPLAY INVISIBLE (-495 2482);
FORCEPROP 1 LAST HDL_POWER GND
J 0
(-450 2675);
DISPLAY 0.872340 (-450 2675);
PAINT GREEN (-450 2675);
DISPLAY INVISIBLE (-450 2675);
FORCEADD PVPP_ABC..1
(-450 3575);
FORCEPROP 3 LASTPIN (-450 3525) SIG_NAME PVPP_ABC\g
J 0
(-440 3535);
DISPLAY 0.659574 (-440 3535);
PAINT MONO (-440 3535);
DISPLAY INVISIBLE (-440 3535);
FORCEPROP 1 LAST VOLTAGE 2.5V
J 0
(-495 3532);
DISPLAY 0.340426 (-495 3532);
PAINT SKYBLUE (-495 3532);
DISPLAY INVISIBLE (-495 3532);
FORCEPROP 2 LAST CDS_LIB mstr_symbols
J 0
(-450 3575);
PAINT ORANGE (-450 3575);
DISPLAY INVISIBLE (-450 3575);
FORCEPROP 1 LAST PATH I17
J 0
(-400 3600);
DISPLAY 0.872340 (-400 3600);
PAINT AQUA (-400 3600);
DISPLAY INVISIBLE (-400 3600);
FORCEPROP 1 LAST BODY_TYPE PLUMBING
J 0
(-495 3532);
DISPLAY 0.340426 (-495 3532);
PAINT GREEN (-495 3532);
DISPLAY INVISIBLE (-495 3532);
FORCEPROP 1 LAST HDL_POWER PVPP_ABC
J 1
(-450 3625);
DISPLAY 0.872340 (-450 3625);
PAINT GREEN (-450 3625);
DISPLAY INVISIBLE (-450 3625);
FORCEADD RES..1
(-2250 2725);
FORCEPROP 1 LAST VALUE 0.0
J 2
(-2275 2625);
DISPLAY 0.617021 (-2275 2625);
PAINT SKYBLUE (-2275 2625);
FORCEPROP 1 LAST TOLERANCE 5%
J 0
(-2250 2625);
DISPLAY 0.617021 (-2250 2625);
PAINT SKYBLUE (-2250 2625);
FORCEPROP 1 LASTPIN (-2350 2725) $PN 1
J 0
(-2338 2737);
DISPLAY 0.617021 (-2338 2737);
PAINT ORANGE (-2338 2737);
FORCEPROP 1 LASTPIN (-2150 2725) $PN 2
J 0
(-2188 2737);
DISPLAY 0.617021 (-2188 2737);
PAINT ORANGE (-2188 2737);
FORCEPROP 1 LAST LOCATION R4T1
J 0
(-2300 2775);
DISPLAY 0.617021 (-2300 2775);
PAINT AQUA (-2300 2775);
FORCEPROP 1 LAST PART_NUMBER G21497-005
J 0
(-2300 2825);
DISPLAY 0.617021 (-2300 2825);
PAINT BLUE (-2300 2825);
FORCEPROP 1 LAST PACK_TYPE 0402
J 0
(-2100 2575);
DISPLAY 0.617021 (-2100 2575);
PAINT SKYBLUE (-2100 2575);
FORCEPROP 1 LAST MATERIAL CHIP
J 0
(-2250 2575);
DISPLAY 0.617021 (-2250 2575);
PAINT SKYBLUE (-2250 2575);
FORCEPROP 1 LAST WATTAGE 1/16W
J 2
(-2275 2575);
DISPLAY 0.617021 (-2275 2575);
PAINT SKYBLUE (-2275 2575);
FORCEPROP 0 LAST ROOM NV_DIMM
J 0
(-2300 2875);
DISPLAY 1.021277 (-2300 2875);
PAINT ORANGE (-2300 2875);
DISPLAY INVISIBLE (-2300 2875);
FORCEPROP 1 LAST PATH I2
J 0
(-2300 2875);
DISPLAY 0.978723 (-2300 2875);
PAINT WHITE (-2300 2875);
DISPLAY INVISIBLE (-2300 2875);
FORCEPROP 2 LAST CDS_LOCATION R4T1
J 0
(-2300 2775);
DISPLAY 0.617021 (-2300 2775);
PAINT AQUA (-2300 2775);
DISPLAY INVISIBLE (-2300 2775);
FORCEPROP 0 LAST SEC 1
J 0
(-2300 2875);
DISPLAY 0.680851 (-2300 2875);
PAINT MONO (-2300 2875);
DISPLAY INVISIBLE (-2300 2875);
FORCEPROP 2 LAST CDS_LIB mstr_discrete
J 0
(-2250 2725);
PAINT ORANGE (-2250 2725);
DISPLAY INVISIBLE (-2250 2725);
FORCEPROP 0 LAST BOM_COST MEM_NV
J 0
(-2300 2925);
DISPLAY 1.021277 (-2300 2925);
PAINT ORANGE (-2300 2925);
DISPLAY INVISIBLE (-2300 2925);
FORCEPROP 2 LAST SEC_TYPE 0402
J 0
(-2300 2925);
DISPLAY 1.021277 (-2300 2925);
PAINT ORANGE (-2300 2925);
DISPLAY INVISIBLE (-2300 2925);
FORCEADD OFFPAGE..2
(3900 3525);
FORCEPROP 2 LAST $XR3 120 
J 0
(4449 3525);
DISPLAY 0.638298 (4449 3525);
PAINT MONO (4449 3525);
FORCEPROP 2 LAST $XR2 191 
J 0
(4329 3525);
DISPLAY 0.638298 (4329 3525);
PAINT MONO (4329 3525);
FORCEPROP 2 LAST $XR1 157 
J 0
(4209 3525);
DISPLAY 0.638298 (4209 3525);
PAINT MONO (4209 3525);
FORCEPROP 2 LAST $XR0 156 
J 0
(4089 3525);
DISPLAY 0.638298 (4089 3525);
PAINT MONO (4089 3525);
FORCEPROP 2 LAST PATH I22
J 0
(4075 3600);
DISPLAY 1.021277 (4075 3600);
PAINT ORANGE (4075 3600);
DISPLAY INVISIBLE (4075 3600);
FORCEPROP 2 LAST CDS_LIB mstr_standard
J 0
(3900 3525);
PAINT MONO (3900 3525);
DISPLAY INVISIBLE (3900 3525);
FORCEPROP 1 LAST OFFPAGE TRUE
J 0
(4225 3400);
DISPLAY 0.872340 (4225 3400);
PAINT GREEN (4225 3400);
DISPLAY INVISIBLE (4225 3400);
FORCEPROP 1 LAST COMMENT_BODY TRUE
J 0
(3855 3430);
DISPLAY 0.872340 (3855 3430);
PAINT GREEN (3855 3430);
DISPLAY INVISIBLE (3855 3430);
FORCEADD RES..1
(3225 3525);
FORCEPROP 1 LAST VALUE 0.0
J 2
(3200 3425);
DISPLAY 0.617021 (3200 3425);
PAINT SKYBLUE (3200 3425);
FORCEPROP 1 LAST MATERIAL EMPTY
J 0
(3525 3425);
DISPLAY 0.617021 (3525 3425);
PAINT RED (3525 3425);
FORCEPROP 1 LAST LOCATION R2P12
J 0
(3175 3575);
DISPLAY 0.617021 (3175 3575);
PAINT AQUA (3175 3575);
FORCEPROP 1 LAST TOLERANCE 5%
J 0
(3225 3425);
DISPLAY 0.617021 (3225 3425);
PAINT SKYBLUE (3225 3425);
FORCEPROP 1 LAST PART_NUMBER G21497-005
J 0
(3175 3625);
DISPLAY 0.617021 (3175 3625);
PAINT BLUE (3175 3625);
FORCEPROP 1 LAST WATTAGE 1/16W
J 2
(3500 3425);
DISPLAY 0.617021 (3500 3425);
PAINT SKYBLUE (3500 3425);
FORCEPROP 1 LAST PACK_TYPE 0402
J 0
(3775 3425);
DISPLAY 0.617021 (3775 3425);
PAINT SKYBLUE (3775 3425);
FORCEPROP 0 LAST BOM_COST MEM_NV
J 0
(3175 3825);
DISPLAY 1.021277 (3175 3825);
PAINT ORANGE (3175 3825);
DISPLAY INVISIBLE (3175 3825);
FORCEPROP 2 LAST CDS_SEC 1
J 0
(3175 3725);
PAINT MONO (3175 3725);
DISPLAY INVISIBLE (3175 3725);
FORCEPROP 2 LAST $SEC 1
J 0
(3175 3725);
PAINT MONO (3175 3725);
DISPLAY INVISIBLE (3175 3725);
FORCEPROP 0 LAST ROOM NV_DIMM
J 0
(3175 3725);
DISPLAY 1.021277 (3175 3725);
PAINT ORANGE (3175 3725);
DISPLAY INVISIBLE (3175 3725);
FORCEPROP 1 LAST PATH I23
J 0
(3175 3675);
DISPLAY 0.978723 (3175 3675);
PAINT WHITE (3175 3675);
DISPLAY INVISIBLE (3175 3675);
FORCEPROP 1 LASTPIN (3325 3525) $PN 2
J 0
(3287 3537);
DISPLAY 0.787234 (3287 3537);
PAINT ORANGE (3287 3537);
DISPLAY INVISIBLE (3287 3537);
FORCEPROP 2 LAST CDS_LOCATION R2P12
J 0
(3175 3575);
DISPLAY 0.617021 (3175 3575);
PAINT AQUA (3175 3575);
DISPLAY INVISIBLE (3175 3575);
FORCEPROP 1 LASTPIN (3125 3525) $PN 1
J 0
(3137 3537);
DISPLAY 0.787234 (3137 3537);
PAINT ORANGE (3137 3537);
DISPLAY INVISIBLE (3137 3537);
FORCEPROP 2 LAST CDS_LIB mstr_discrete
J 0
(3225 3525);
PAINT MONO (3225 3525);
DISPLAY INVISIBLE (3225 3525);
FORCEADD RES..2
(1750 4500);
FORCEPROP 1 LAST PACK_TYPE 0402
J 0
(1790 4325);
DISPLAY 0.617021 (1790 4325);
PAINT SKYBLUE (1790 4325);
FORCEPROP 1 LAST PART_NUMBER G21796-072
J 0
(1790 4375);
DISPLAY 0.617021 (1790 4375);
PAINT BLUE (1790 4375);
FORCEPROP 1 LAST VALUE 4.75K
J 0
(1795 4575);
DISPLAY 0.617021 (1795 4575);
PAINT SKYBLUE (1795 4575);
FORCEPROP 1 LAST WATTAGE 1/16W
J 0
(1790 4475);
DISPLAY 0.617021 (1790 4475);
PAINT SKYBLUE (1790 4475);
FORCEPROP 1 LAST MATERIAL CHIP
J 0
(1790 4425);
DISPLAY 0.617021 (1790 4425);
PAINT SKYBLUE (1790 4425);
FORCEPROP 1 LAST TOLERANCE 1%
J 0
(1795 4525);
DISPLAY 0.617021 (1795 4525);
PAINT SKYBLUE (1795 4525);
FORCEPROP 1 LAST LOCATION R8D29
J 0
(1795 4625);
DISPLAY 0.617021 (1795 4625);
PAINT AQUA (1795 4625);
FORCEPROP 1 LASTPIN (1750 4400) $PN 2
J 0
(1755 4410);
DISPLAY 0.787234 (1755 4410);
PAINT ORANGE (1755 4410);
DISPLAY INVISIBLE (1755 4410);
FORCEPROP 2 LAST CDS_LIB mstr_discrete
J 0
(1750 4500);
PAINT MONO (1750 4500);
DISPLAY INVISIBLE (1750 4500);
FORCEPROP 1 LASTPIN (1750 4600) $PN 1
J 0
(1755 4562);
DISPLAY 0.787234 (1755 4562);
PAINT ORANGE (1755 4562);
DISPLAY INVISIBLE (1755 4562);
FORCEPROP 1 LAST PATH I26
J 0
(1800 4675);
DISPLAY 0.978723 (1800 4675);
PAINT WHITE (1800 4675);
DISPLAY INVISIBLE (1800 4675);
FORCEPROP 2 LAST CDS_LOCATION R8D29
J 0
(1795 4625);
DISPLAY 0.617021 (1795 4625);
PAINT AQUA (1795 4625);
DISPLAY INVISIBLE (1795 4625);
FORCEPROP 0 LAST ROOM NVDIMM
J 0
(1800 4725);
DISPLAY 1.021277 (1800 4725);
PAINT ORANGE (1800 4725);
DISPLAY INVISIBLE (1800 4725);
FORCEPROP 2 LAST $SEC 1
J 0
(1800 4725);
PAINT MONO (1800 4725);
DISPLAY INVISIBLE (1800 4725);
FORCEPROP 2 LAST CDS_SEC 1
J 0
(1800 4725);
PAINT MONO (1800 4725);
DISPLAY INVISIBLE (1800 4725);
FORCEADD RES..2
(2450 4725);
FORCEPROP 1 LAST PACK_TYPE 0402
J 0
(2490 4550);
DISPLAY 0.617021 (2490 4550);
PAINT SKYBLUE (2490 4550);
FORCEPROP 1 LAST PART_NUMBER G21796-072
J 0
(2490 4600);
DISPLAY 0.617021 (2490 4600);
PAINT BLUE (2490 4600);
FORCEPROP 1 LAST LOCATION R8D31
J 0
(2495 4850);
DISPLAY 0.617021 (2495 4850);
PAINT AQUA (2495 4850);
FORCEPROP 1 LAST TOLERANCE 1%
J 0
(2495 4750);
DISPLAY 0.617021 (2495 4750);
PAINT SKYBLUE (2495 4750);
FORCEPROP 1 LAST VALUE 4.75K
J 0
(2495 4800);
DISPLAY 0.617021 (2495 4800);
PAINT SKYBLUE (2495 4800);
FORCEPROP 1 LAST MATERIAL CHIP
J 0
(2490 4650);
DISPLAY 0.617021 (2490 4650);
PAINT SKYBLUE (2490 4650);
FORCEPROP 1 LAST WATTAGE 1/16W
J 0
(2490 4700);
DISPLAY 0.617021 (2490 4700);
PAINT SKYBLUE (2490 4700);
FORCEPROP 2 LAST CDS_SEC 1
J 0
(2500 4950);
PAINT MONO (2500 4950);
DISPLAY INVISIBLE (2500 4950);
FORCEPROP 2 LAST $SEC 1
J 0
(2500 4950);
PAINT MONO (2500 4950);
DISPLAY INVISIBLE (2500 4950);
FORCEPROP 2 LAST CDS_LOCATION R8D31
J 0
(2495 4850);
DISPLAY 0.617021 (2495 4850);
PAINT AQUA (2495 4850);
DISPLAY INVISIBLE (2495 4850);
FORCEPROP 1 LAST PATH I27
J 0
(2500 4900);
DISPLAY 0.978723 (2500 4900);
PAINT WHITE (2500 4900);
DISPLAY INVISIBLE (2500 4900);
FORCEPROP 0 LAST ROOM NVDIMM
J 0
(2500 4950);
DISPLAY 1.021277 (2500 4950);
PAINT ORANGE (2500 4950);
DISPLAY INVISIBLE (2500 4950);
FORCEPROP 2 LAST CDS_LIB mstr_discrete
J 0
(2450 4725);
PAINT MONO (2450 4725);
DISPLAY INVISIBLE (2450 4725);
FORCEPROP 1 LASTPIN (2450 4825) $PN 1
J 0
(2455 4787);
DISPLAY 0.787234 (2455 4787);
PAINT ORANGE (2455 4787);
DISPLAY INVISIBLE (2455 4787);
FORCEPROP 1 LASTPIN (2450 4625) $PN 2
J 0
(2455 4635);
DISPLAY 0.787234 (2455 4635);
PAINT ORANGE (2455 4635);
DISPLAY INVISIBLE (2455 4635);
FORCEADD P3V3_STBY..1
(1750 4725);
FORCEPROP 3 LASTPIN (1750 4675) SIG_NAME P3V3_STBY\g
J 0
(1760 4685);
DISPLAY 0.659574 (1760 4685);
PAINT MONO (1760 4685);
DISPLAY INVISIBLE (1760 4685);
FORCEPROP 1 LAST VOLTAGE 3.3V
J 0
(1705 4682);
DISPLAY 0.340426 (1705 4682);
PAINT SKYBLUE (1705 4682);
DISPLAY INVISIBLE (1705 4682);
FORCEPROP 1 LAST PATH I28
J 0
(1795 4727);
DISPLAY 0.340426 (1795 4727);
PAINT GREEN (1795 4727);
DISPLAY INVISIBLE (1795 4727);
FORCEPROP 1 LAST SIZE 1B
J 0
(1795 4747);
DISPLAY 0.340426 (1795 4747);
PAINT GREEN (1795 4747);
DISPLAY INVISIBLE (1795 4747);
FORCEPROP 2 LAST CDS_LIB mstr_symbols
J 0
(1750 4725);
PAINT MONO (1750 4725);
DISPLAY INVISIBLE (1750 4725);
FORCEPROP 1 LAST BODY_TYPE PLUMBING
J 0
(1705 4682);
DISPLAY 0.340426 (1705 4682);
PAINT GREEN (1705 4682);
DISPLAY INVISIBLE (1705 4682);
FORCEPROP 1 LAST HDL_POWER P3V3_STBY
J 0
(1450 4600);
DISPLAY 0.872340 (1450 4600);
PAINT ORANGE (1450 4600);
DISPLAY INVISIBLE (1450 4600);
FORCEADD P3V3_STBY..1
(2450 4950);
FORCEPROP 3 LASTPIN (2450 4900) SIG_NAME P3V3_STBY\g
J 0
(2460 4910);
DISPLAY 0.659574 (2460 4910);
PAINT MONO (2460 4910);
DISPLAY INVISIBLE (2460 4910);
FORCEPROP 1 LAST SIZE 1B
J 0
(2495 4972);
DISPLAY 0.340426 (2495 4972);
PAINT GREEN (2495 4972);
DISPLAY INVISIBLE (2495 4972);
FORCEPROP 1 LAST PATH I29
J 0
(2495 4952);
DISPLAY 0.340426 (2495 4952);
PAINT GREEN (2495 4952);
DISPLAY INVISIBLE (2495 4952);
FORCEPROP 2 LAST CDS_LIB mstr_symbols
J 0
(2450 4950);
PAINT MONO (2450 4950);
DISPLAY INVISIBLE (2450 4950);
FORCEPROP 1 LAST VOLTAGE 3.3V
J 0
(2405 4907);
DISPLAY 0.340426 (2405 4907);
PAINT SKYBLUE (2405 4907);
DISPLAY INVISIBLE (2405 4907);
FORCEPROP 1 LAST BODY_TYPE PLUMBING
J 0
(2405 4907);
DISPLAY 0.340426 (2405 4907);
PAINT GREEN (2405 4907);
DISPLAY INVISIBLE (2405 4907);
FORCEPROP 1 LAST HDL_POWER P3V3_STBY
J 0
(2150 4825);
DISPLAY 0.872340 (2150 4825);
PAINT ORANGE (2150 4825);
DISPLAY INVISIBLE (2150 4825);
FORCEADD RES..1
(350 3125);
FORCEPROP 1 LAST WATTAGE 1/16W
J 2
(325 2975);
DISPLAY 0.617021 (325 2975);
PAINT SKYBLUE (325 2975);
FORCEPROP 1 LAST TOLERANCE 1%
J 0
(350 3025);
DISPLAY 0.617021 (350 3025);
PAINT SKYBLUE (350 3025);
FORCEPROP 1 LAST PART_NUMBER G21796-047
J 0
(300 3225);
DISPLAY 0.617021 (300 3225);
PAINT BLUE (300 3225);
FORCEPROP 1 LAST PACK_TYPE 0402
J 0
(600 2975);
DISPLAY 0.617021 (600 2975);
PAINT SKYBLUE (600 2975);
FORCEPROP 1 LAST LOCATION R6F4
J 0
(300 3175);
DISPLAY 0.617021 (300 3175);
PAINT AQUA (300 3175);
FORCEPROP 1 LASTPIN (450 3125) $PN 2
J 0
(412 3137);
DISPLAY 0.617021 (412 3137);
PAINT ORANGE (412 3137);
FORCEPROP 1 LASTPIN (250 3125) $PN 1
J 0
(262 3137);
DISPLAY 0.617021 (262 3137);
PAINT ORANGE (262 3137);
FORCEPROP 1 LAST VALUE 49.9
J 2
(325 3025);
DISPLAY 0.617021 (325 3025);
PAINT SKYBLUE (325 3025);
FORCEPROP 1 LAST MATERIAL CHIP
J 0
(350 2975);
DISPLAY 0.617021 (350 2975);
PAINT SKYBLUE (350 2975);
FORCEPROP 0 LAST BOM_COST MEM_NV
J 0
(300 3325);
DISPLAY 1.021277 (300 3325);
PAINT ORANGE (300 3325);
DISPLAY INVISIBLE (300 3325);
FORCEPROP 2 LAST SEC_TYPE 0402
J 0
(300 3325);
DISPLAY 1.021277 (300 3325);
PAINT ORANGE (300 3325);
DISPLAY INVISIBLE (300 3325);
FORCEPROP 0 LAST SEC 1
J 0
(300 3275);
DISPLAY 0.680851 (300 3275);
PAINT MONO (300 3275);
DISPLAY INVISIBLE (300 3275);
FORCEPROP 1 LAST PATH I3
J 0
(300 3275);
DISPLAY 0.978723 (300 3275);
PAINT WHITE (300 3275);
DISPLAY INVISIBLE (300 3275);
FORCEPROP 0 LAST ROOM NV_DIMM
J 0
(300 3275);
DISPLAY 1.021277 (300 3275);
PAINT ORANGE (300 3275);
DISPLAY INVISIBLE (300 3275);
FORCEPROP 2 LAST CDS_LOCATION R6F4
J 0
(300 3175);
DISPLAY 0.617021 (300 3175);
PAINT AQUA (300 3175);
DISPLAY INVISIBLE (300 3175);
FORCEPROP 2 LAST CDS_LIB mstr_discrete
J 0
(350 3125);
PAINT ORANGE (350 3125);
DISPLAY INVISIBLE (350 3125);
FORCEADD GND..1
(2450 3950);
FORCEPROP 3 LASTPIN (2450 4000) SIG_NAME GND\g
J 0
(2460 4010);
DISPLAY 0.659574 (2460 4010);
PAINT MONO (2460 4010);
DISPLAY INVISIBLE (2460 4010);
FORCEPROP 1 LAST SIZE 1B
J 0
(2525 3900);
DISPLAY 0.872340 (2525 3900);
PAINT AQUA (2525 3900);
DISPLAY INVISIBLE (2525 3900);
FORCEPROP 2 LAST CDS_LIB mstr_symbols
J 0
(2450 3950);
PAINT MONO (2450 3950);
DISPLAY INVISIBLE (2450 3950);
FORCEPROP 1 LAST VOLTAGE 0.0V
J 0
(2405 3907);
DISPLAY 0.340426 (2405 3907);
PAINT SKYBLUE (2405 3907);
DISPLAY INVISIBLE (2405 3907);
FORCEPROP 1 LAST PATH I30
J 0
(2525 3950);
DISPLAY 0.872340 (2525 3950);
PAINT AQUA (2525 3950);
DISPLAY INVISIBLE (2525 3950);
FORCEPROP 1 LAST BODY_TYPE PLUMBING
J 0
(2405 3907);
DISPLAY 0.340426 (2405 3907);
PAINT GREEN (2405 3907);
DISPLAY INVISIBLE (2405 3907);
FORCEPROP 1 LAST HDL_POWER GND
J 0
(2450 4100);
DISPLAY 0.872340 (2450 4100);
PAINT GREEN (2450 4100);
DISPLAY INVISIBLE (2450 4100);
FORCEADD GND..1
(1750 3475);
FORCEPROP 3 LASTPIN (1750 3525) SIG_NAME GND\g
J 0
(1760 3535);
DISPLAY 0.659574 (1760 3535);
PAINT MONO (1760 3535);
DISPLAY INVISIBLE (1760 3535);
FORCEPROP 1 LAST SIZE 1B
J 0
(1825 3425);
DISPLAY 0.872340 (1825 3425);
PAINT AQUA (1825 3425);
DISPLAY INVISIBLE (1825 3425);
FORCEPROP 1 LAST VOLTAGE 0.0V
J 0
(1705 3432);
DISPLAY 0.340426 (1705 3432);
PAINT SKYBLUE (1705 3432);
DISPLAY INVISIBLE (1705 3432);
FORCEPROP 2 LAST CDS_LIB mstr_symbols
J 0
(1750 3475);
PAINT MONO (1750 3475);
DISPLAY INVISIBLE (1750 3475);
FORCEPROP 1 LAST PATH I31
J 0
(1825 3475);
DISPLAY 0.872340 (1825 3475);
PAINT AQUA (1825 3475);
DISPLAY INVISIBLE (1825 3475);
FORCEPROP 1 LAST BODY_TYPE PLUMBING
J 0
(1705 3432);
DISPLAY 0.340426 (1705 3432);
PAINT GREEN (1705 3432);
DISPLAY INVISIBLE (1705 3432);
FORCEPROP 1 LAST HDL_POWER GND
J 0
(1750 3625);
DISPLAY 0.872340 (1750 3625);
PAINT GREEN (1750 3625);
DISPLAY INVISIBLE (1750 3625);
FORCEADD OFFPAGE..2
(3500 4550);
FORCEPROP 2 LAST $XR1 145 
J 0
(3809 4550);
DISPLAY 0.638298 (3809 4550);
PAINT MONO (3809 4550);
FORCEPROP 2 LAST $XR0 120 
J 0
(3689 4550);
DISPLAY 0.638298 (3689 4550);
PAINT MONO (3689 4550);
FORCEPROP 2 LAST CDS_LIB mstr_standard
J 0
(3500 4550);
PAINT MONO (3500 4550);
DISPLAY INVISIBLE (3500 4550);
FORCEPROP 2 LAST PATH I33
J 0
(3550 4625);
DISPLAY 1.021277 (3550 4625);
PAINT ORANGE (3550 4625);
DISPLAY INVISIBLE (3550 4625);
FORCEPROP 1 LAST OFFPAGE TRUE
J 0
(3825 4425);
DISPLAY 0.872340 (3825 4425);
PAINT GREEN (3825 4425);
DISPLAY INVISIBLE (3825 4425);
FORCEPROP 1 LAST COMMENT_BODY TRUE
J 0
(3455 4455);
DISPLAY 0.872340 (3455 4455);
PAINT GREEN (3455 4455);
DISPLAY INVISIBLE (3455 4455);
FORCEADD RES..1
(775 3700);
FORCEPROP 1 LAST MATERIAL CHIP
J 0
(775 3550);
DISPLAY 0.617021 (775 3550);
PAINT SKYBLUE (775 3550);
FORCEPROP 1 LAST PACK_TYPE 0402
J 0
(1025 3550);
DISPLAY 0.617021 (1025 3550);
PAINT SKYBLUE (1025 3550);
FORCEPROP 1 LAST TOLERANCE 1%
J 0
(775 3600);
DISPLAY 0.617021 (775 3600);
PAINT SKYBLUE (775 3600);
FORCEPROP 1 LASTPIN (875 3700) $PN 2
J 0
(837 3712);
DISPLAY 0.617021 (837 3712);
PAINT ORANGE (837 3712);
FORCEPROP 1 LAST PART_NUMBER G21796-016
J 0
(725 3800);
DISPLAY 0.617021 (725 3800);
PAINT BLUE (725 3800);
FORCEPROP 1 LAST WATTAGE 1/16W
J 2
(750 3550);
DISPLAY 0.617021 (750 3550);
PAINT SKYBLUE (750 3550);
FORCEPROP 1 LAST VALUE 10.0K
J 2
(750 3600);
DISPLAY 0.617021 (750 3600);
PAINT SKYBLUE (750 3600);
FORCEPROP 1 LAST LOCATION R8D30
J 0
(725 3750);
DISPLAY 0.617021 (725 3750);
PAINT AQUA (725 3750);
FORCEPROP 1 LASTPIN (675 3700) $PN 1
J 0
(687 3712);
DISPLAY 0.617021 (687 3712);
PAINT ORANGE (687 3712);
FORCEPROP 1 LAST PATH I34
J 0
(725 3850);
DISPLAY 0.978723 (725 3850);
PAINT WHITE (725 3850);
DISPLAY INVISIBLE (725 3850);
FORCEPROP 2 LAST SEC_TYPE 0402
J 0
(725 3900);
DISPLAY 1.021277 (725 3900);
PAINT ORANGE (725 3900);
DISPLAY INVISIBLE (725 3900);
FORCEPROP 2 LAST CDS_LIB mstr_discrete
J 0
(775 3700);
PAINT ORANGE (775 3700);
DISPLAY INVISIBLE (775 3700);
FORCEPROP 0 LAST BOM_COST MEM_NV
J 0
(725 3900);
DISPLAY 1.021277 (725 3900);
PAINT ORANGE (725 3900);
DISPLAY INVISIBLE (725 3900);
FORCEPROP 2 LAST SEC 1
J 0
(725 3900);
DISPLAY 0.680851 (725 3900);
PAINT MONO (725 3900);
DISPLAY INVISIBLE (725 3900);
FORCEPROP 2 LAST CDS_LOCATION R8D30
J 0
(725 3750);
DISPLAY 0.617021 (725 3750);
PAINT AQUA (725 3750);
DISPLAY INVISIBLE (725 3750);
FORCEPROP 0 LAST ROOM NV_DIMM
J 0
(725 3850);
DISPLAY 1.021277 (725 3850);
PAINT ORANGE (725 3850);
DISPLAY INVISIBLE (725 3850);
FORCEADD NPN_DUAL..1
(1700 3700);
FORCEPROP 1 LAST VALUE MBT3904
J 0
(1800 3750);
DISPLAY 0.617021 (1800 3750);
PAINT SKYBLUE (1800 3750);
FORCEPROP 1 LAST MATERIAL XSTR
J 0
(1800 3700);
DISPLAY 0.617021 (1800 3700);
PAINT SKYBLUE (1800 3700);
FORCEPROP 1 LAST LOCATION Q8D1
J 0
(1800 3800);
DISPLAY 0.617021 (1800 3800);
PAINT AQUA (1800 3800);
FORCEPROP 1 LASTPIN (1750 3800) $PN 3
J 0
(1690 3760);
DISPLAY 0.617021 (1690 3760);
PAINT AQUA (1690 3760);
FORCEPROP 1 LASTPIN (1600 3700) $PN 5
J 0
(1615 3705);
DISPLAY 0.617021 (1615 3705);
PAINT AQUA (1615 3705);
FORCEPROP 1 LASTPIN (1750 3600) $PN 4
J 2
(1740 3600);
DISPLAY 0.617021 (1740 3600);
PAINT AQUA (1740 3600);
FORCEPROP 1 LAST PART_NUMBER C52264-001
J 0
(1800 3650);
DISPLAY 0.617021 (1800 3650);
PAINT BLUE (1800 3650);
FORCEPROP 0 LAST ROOM NV_DIMM
J 0
(1800 3900);
DISPLAY 1.021277 (1800 3900);
PAINT ORANGE (1800 3900);
DISPLAY INVISIBLE (1800 3900);
FORCEPROP 2 LAST SEC 1
J 0
(1800 3850);
DISPLAY 0.680851 (1800 3850);
PAINT MONO (1800 3850);
DISPLAY INVISIBLE (1800 3850);
FORCEPROP 2 LAST CDS_LIB mstr_discrete
J 0
(1700 3700);
PAINT ORANGE (1700 3700);
DISPLAY INVISIBLE (1700 3700);
FORCEPROP 2 LAST SEC_TYPE SSOPLF
J 0
(1800 3850);
DISPLAY 1.021277 (1800 3850);
PAINT ORANGE (1800 3850);
DISPLAY INVISIBLE (1800 3850);
FORCEPROP 0 LAST BOM_COST MEM_NV
J 0
(1800 3900);
DISPLAY 1.021277 (1800 3900);
PAINT ORANGE (1800 3900);
DISPLAY INVISIBLE (1800 3900);
FORCEPROP 1 LAST PACK_TYPE SSOPLF
J 0
(1800 3850);
DISPLAY 0.978723 (1800 3850);
PAINT SKYBLUE (1800 3850);
DISPLAY INVISIBLE (1800 3850);
FORCEPROP 1 LAST PATH I35
J 0
(2200 3700);
DISPLAY 0.978723 (2200 3700);
PAINT BLUE (2200 3700);
DISPLAY INVISIBLE (2200 3700);
FORCEPROP 2 LAST CDS_LOCATION Q8D1
J 0
(1800 3800);
DISPLAY 0.617021 (1800 3800);
PAINT AQUA (1800 3800);
DISPLAY INVISIBLE (1800 3800);
FORCEADD GND..1
(-450 1350);
FORCEPROP 3 LASTPIN (-450 1400) SIG_NAME GND\g
J 0
(-440 1410);
DISPLAY 0.659574 (-440 1410);
PAINT MONO (-440 1410);
DISPLAY INVISIBLE (-440 1410);
FORCEPROP 1 LAST PATH I39
J 0
(-375 1350);
DISPLAY 0.872340 (-375 1350);
PAINT AQUA (-375 1350);
DISPLAY INVISIBLE (-375 1350);
FORCEPROP 1 LAST SIZE 1B
J 0
(-375 1300);
DISPLAY 0.872340 (-375 1300);
PAINT AQUA (-375 1300);
DISPLAY INVISIBLE (-375 1300);
FORCEPROP 2 LAST CDS_LIB mstr_symbols
J 0
(-450 1350);
PAINT ORANGE (-450 1350);
DISPLAY INVISIBLE (-450 1350);
FORCEPROP 1 LAST VOLTAGE 0.0V
J 0
(-495 1307);
DISPLAY 0.340426 (-495 1307);
PAINT SKYBLUE (-495 1307);
DISPLAY INVISIBLE (-495 1307);
FORCEPROP 1 LAST BODY_TYPE PLUMBING
J 0
(-495 1307);
DISPLAY 0.340426 (-495 1307);
PAINT GREEN (-495 1307);
DISPLAY INVISIBLE (-495 1307);
FORCEPROP 1 LAST HDL_POWER GND
J 0
(-450 1500);
DISPLAY 0.872340 (-450 1500);
PAINT GREEN (-450 1500);
DISPLAY INVISIBLE (-450 1500);
FORCEADD RES..1
(350 2825);
FORCEPROP 1 LAST VALUE 49.9
J 2
(325 2725);
DISPLAY 0.617021 (325 2725);
PAINT SKYBLUE (325 2725);
FORCEPROP 1 LASTPIN (250 2825) $PN 1
J 0
(262 2837);
DISPLAY 0.617021 (262 2837);
PAINT ORANGE (262 2837);
FORCEPROP 1 LAST PART_NUMBER G21796-047
J 0
(300 2925);
DISPLAY 0.617021 (300 2925);
PAINT BLUE (300 2925);
FORCEPROP 1 LAST PACK_TYPE 0402
J 0
(600 2675);
DISPLAY 0.617021 (600 2675);
PAINT SKYBLUE (600 2675);
FORCEPROP 1 LAST TOLERANCE 1%
J 0
(350 2725);
DISPLAY 0.617021 (350 2725);
PAINT SKYBLUE (350 2725);
FORCEPROP 1 LASTPIN (450 2825) $PN 2
J 0
(412 2837);
DISPLAY 0.617021 (412 2837);
PAINT ORANGE (412 2837);
FORCEPROP 1 LAST MATERIAL CHIP
J 0
(350 2675);
DISPLAY 0.617021 (350 2675);
PAINT SKYBLUE (350 2675);
FORCEPROP 1 LAST WATTAGE 1/16W
J 2
(325 2675);
DISPLAY 0.617021 (325 2675);
PAINT SKYBLUE (325 2675);
FORCEPROP 1 LAST LOCATION R6F1
J 0
(300 2875);
DISPLAY 0.617021 (300 2875);
PAINT AQUA (300 2875);
FORCEPROP 0 LAST ROOM NV_DIMM
J 0
(300 2975);
DISPLAY 1.021277 (300 2975);
PAINT ORANGE (300 2975);
DISPLAY INVISIBLE (300 2975);
FORCEPROP 1 LAST PATH I4
J 0
(300 2975);
DISPLAY 0.978723 (300 2975);
PAINT WHITE (300 2975);
DISPLAY INVISIBLE (300 2975);
FORCEPROP 0 LAST SEC 1
J 0
(300 2975);
DISPLAY 0.680851 (300 2975);
PAINT MONO (300 2975);
DISPLAY INVISIBLE (300 2975);
FORCEPROP 2 LAST SEC_TYPE 0402
J 0
(300 3025);
DISPLAY 1.021277 (300 3025);
PAINT ORANGE (300 3025);
DISPLAY INVISIBLE (300 3025);
FORCEPROP 0 LAST BOM_COST MEM_NV
J 0
(300 3025);
DISPLAY 1.021277 (300 3025);
PAINT ORANGE (300 3025);
DISPLAY INVISIBLE (300 3025);
FORCEPROP 2 LAST CDS_LIB mstr_discrete
J 0
(350 2825);
PAINT ORANGE (350 2825);
DISPLAY INVISIBLE (350 2825);
FORCEPROP 2 LAST CDS_LOCATION R6F1
J 0
(300 2875);
DISPLAY 0.617021 (300 2875);
PAINT AQUA (300 2875);
DISPLAY INVISIBLE (300 2875);
FORCEADD RES..2
(-450 2175);
FORCEPROP 1 LAST WATTAGE 1/16W
J 0
(-410 2150);
DISPLAY 0.617021 (-410 2150);
PAINT SKYBLUE (-410 2150);
FORCEPROP 1 LAST TOLERANCE 1%
J 0
(-405 2200);
DISPLAY 0.617021 (-405 2200);
PAINT SKYBLUE (-405 2200);
FORCEPROP 1 LASTPIN (-450 2075) $PN 2
J 0
(-445 2085);
DISPLAY 0.617021 (-445 2085);
PAINT ORANGE (-445 2085);
FORCEPROP 1 LAST MATERIAL CHIP
J 0
(-410 2100);
DISPLAY 0.617021 (-410 2100);
PAINT SKYBLUE (-410 2100);
FORCEPROP 1 LAST PART_NUMBER G21796-016
J 0
(-410 2050);
DISPLAY 0.617021 (-410 2050);
PAINT BLUE (-410 2050);
FORCEPROP 1 LAST PACK_TYPE 0402
J 0
(-410 2000);
DISPLAY 0.617021 (-410 2000);
PAINT SKYBLUE (-410 2000);
FORCEPROP 1 LASTPIN (-450 2275) $PN 1
J 0
(-445 2237);
DISPLAY 0.617021 (-445 2237);
PAINT ORANGE (-445 2237);
FORCEPROP 1 LAST LOCATION R6W29
J 0
(-405 2300);
DISPLAY 0.617021 (-405 2300);
PAINT AQUA (-405 2300);
FORCEPROP 1 LAST VALUE 10.0K
J 0
(-405 2250);
DISPLAY 0.617021 (-405 2250);
PAINT SKYBLUE (-405 2250);
FORCEPROP 2 LAST CDS_LOCATION R6W29
J 0
(-405 2300);
DISPLAY 0.617021 (-405 2300);
PAINT AQUA (-405 2300);
DISPLAY INVISIBLE (-405 2300);
FORCEPROP 0 LAST SEC 1
J 0
(-400 2350);
DISPLAY 0.680851 (-400 2350);
PAINT MONO (-400 2350);
DISPLAY INVISIBLE (-400 2350);
FORCEPROP 2 LAST SEC_TYPE 0402
J 0
(-400 2400);
DISPLAY 1.021277 (-400 2400);
PAINT ORANGE (-400 2400);
DISPLAY INVISIBLE (-400 2400);
FORCEPROP 0 LAST BOM_COST MEM_NV
J 0
(-400 2400);
DISPLAY 1.021277 (-400 2400);
PAINT ORANGE (-400 2400);
DISPLAY INVISIBLE (-400 2400);
FORCEPROP 0 LAST ROOM NV_DIMM
J 0
(-400 2350);
DISPLAY 1.021277 (-400 2350);
PAINT ORANGE (-400 2350);
DISPLAY INVISIBLE (-400 2350);
FORCEPROP 2 LAST CDS_LIB mstr_discrete
J 0
(-450 2175);
PAINT ORANGE (-450 2175);
DISPLAY INVISIBLE (-450 2175);
FORCEPROP 1 LAST PATH I40
J 0
(-400 2350);
DISPLAY 0.978723 (-400 2350);
PAINT WHITE (-400 2350);
DISPLAY INVISIBLE (-400 2350);
FORCEADD PVPP_ABC..1
(-450 2425);
FORCEPROP 3 LASTPIN (-450 2375) SIG_NAME PVPP_ABC\g
J 0
(-440 2385);
DISPLAY 0.659574 (-440 2385);
PAINT MONO (-440 2385);
DISPLAY INVISIBLE (-440 2385);
FORCEPROP 1 LAST VOLTAGE 2.5V
J 0
(-495 2382);
DISPLAY 0.340426 (-495 2382);
PAINT SKYBLUE (-495 2382);
DISPLAY INVISIBLE (-495 2382);
FORCEPROP 2 LAST CDS_LIB mstr_symbols
J 0
(-450 2425);
PAINT ORANGE (-450 2425);
DISPLAY INVISIBLE (-450 2425);
FORCEPROP 1 LAST PATH I41
J 0
(-400 2450);
DISPLAY 0.872340 (-400 2450);
PAINT AQUA (-400 2450);
DISPLAY INVISIBLE (-400 2450);
FORCEPROP 1 LAST BODY_TYPE PLUMBING
J 0
(-495 2382);
DISPLAY 0.340426 (-495 2382);
PAINT GREEN (-495 2382);
DISPLAY INVISIBLE (-495 2382);
FORCEPROP 1 LAST HDL_POWER PVPP_ABC
J 1
(-450 2475);
DISPLAY 0.872340 (-450 2475);
PAINT GREEN (-450 2475);
DISPLAY INVISIBLE (-450 2475);
FORCEADD RES..1
(1000 2500);
FORCEPROP 1 LAST VALUE 10.0K
J 2
(975 2400);
DISPLAY 0.617021 (975 2400);
PAINT SKYBLUE (975 2400);
FORCEPROP 1 LAST WATTAGE 1/16W
J 2
(975 2350);
DISPLAY 0.617021 (975 2350);
PAINT SKYBLUE (975 2350);
FORCEPROP 1 LAST TOLERANCE 1%
J 0
(1000 2400);
DISPLAY 0.617021 (1000 2400);
PAINT SKYBLUE (1000 2400);
FORCEPROP 1 LAST PACK_TYPE 0402
J 0
(1250 2350);
DISPLAY 0.617021 (1250 2350);
PAINT SKYBLUE (1250 2350);
FORCEPROP 1 LAST MATERIAL CHIP
J 0
(1000 2350);
DISPLAY 0.617021 (1000 2350);
PAINT SKYBLUE (1000 2350);
FORCEPROP 1 LASTPIN (1100 2500) $PN 2
J 0
(1062 2512);
DISPLAY 0.617021 (1062 2512);
PAINT ORANGE (1062 2512);
FORCEPROP 1 LAST PART_NUMBER G21796-016
J 0
(950 2600);
DISPLAY 0.617021 (950 2600);
PAINT BLUE (950 2600);
FORCEPROP 1 LASTPIN (900 2500) $PN 1
J 0
(912 2512);
DISPLAY 0.617021 (912 2512);
PAINT ORANGE (912 2512);
FORCEPROP 1 LAST LOCATION WR8D30
J 0
(950 2550);
DISPLAY 0.617021 (950 2550);
PAINT AQUA (950 2550);
FORCEPROP 2 LAST CDS_LOCATION WR8D30
J 0
(950 2550);
DISPLAY 0.617021 (950 2550);
PAINT AQUA (950 2550);
DISPLAY INVISIBLE (950 2550);
FORCEPROP 2 LAST SEC_TYPE 0402
J 0
(950 2700);
DISPLAY 1.021277 (950 2700);
PAINT ORANGE (950 2700);
DISPLAY INVISIBLE (950 2700);
FORCEPROP 2 LAST CDS_LIB mstr_discrete
J 0
(1000 2500);
PAINT ORANGE (1000 2500);
DISPLAY INVISIBLE (1000 2500);
FORCEPROP 0 LAST BOM_COST MEM_NV
J 0
(950 2700);
DISPLAY 1.021277 (950 2700);
PAINT ORANGE (950 2700);
DISPLAY INVISIBLE (950 2700);
FORCEPROP 2 LAST SEC 1
J 0
(950 2700);
DISPLAY 0.680851 (950 2700);
PAINT MONO (950 2700);
DISPLAY INVISIBLE (950 2700);
FORCEPROP 0 LAST ROOM NV_DIMM
J 0
(950 2650);
DISPLAY 1.021277 (950 2650);
PAINT ORANGE (950 2650);
DISPLAY INVISIBLE (950 2650);
FORCEPROP 1 LAST PATH I45
J 0
(950 2650);
DISPLAY 0.978723 (950 2650);
PAINT WHITE (950 2650);
DISPLAY INVISIBLE (950 2650);
FORCEADD NPN_DUAL..1
(2400 4175);
FORCEPROP 1 LAST VALUE MBT3904
J 0
(2500 4225);
DISPLAY 0.617021 (2500 4225);
PAINT SKYBLUE (2500 4225);
FORCEPROP 1 LASTPIN (2450 4075) $PN 1
J 2
(2440 4075);
DISPLAY 0.617021 (2440 4075);
PAINT AQUA (2440 4075);
FORCEPROP 1 LAST MATERIAL XSTR
J 0
(2500 4175);
DISPLAY 0.617021 (2500 4175);
PAINT SKYBLUE (2500 4175);
FORCEPROP 1 LASTPIN (2300 4175) $PN 2
J 0
(2315 4180);
DISPLAY 0.617021 (2315 4180);
PAINT AQUA (2315 4180);
FORCEPROP 1 LAST PART_NUMBER C52264-001
J 0
(2500 4125);
DISPLAY 0.617021 (2500 4125);
PAINT BLUE (2500 4125);
FORCEPROP 1 LAST LOCATION Q8D1
J 0
(2500 4275);
DISPLAY 0.617021 (2500 4275);
PAINT AQUA (2500 4275);
FORCEPROP 1 LASTPIN (2450 4275) $PN 6
J 0
(2390 4235);
DISPLAY 0.617021 (2390 4235);
PAINT AQUA (2390 4235);
FORCEPROP 2 LAST CDS_LIB mstr_discrete
J 0
(2400 4175);
PAINT ORANGE (2400 4175);
DISPLAY INVISIBLE (2400 4175);
FORCEPROP 0 LAST ROOM NV_DIMM
J 0
(2500 4375);
DISPLAY 1.021277 (2500 4375);
PAINT ORANGE (2500 4375);
DISPLAY INVISIBLE (2500 4375);
FORCEPROP 2 LAST SEC 2
J 0
(2500 4325);
DISPLAY 0.680851 (2500 4325);
PAINT MONO (2500 4325);
DISPLAY INVISIBLE (2500 4325);
FORCEPROP 2 LAST SEC_TYPE SSOPLF
J 0
(2500 4325);
DISPLAY 1.021277 (2500 4325);
PAINT ORANGE (2500 4325);
DISPLAY INVISIBLE (2500 4325);
FORCEPROP 0 LAST BOM_COST MEM_NV
J 0
(2500 4475);
DISPLAY 1.021277 (2500 4475);
PAINT ORANGE (2500 4475);
DISPLAY INVISIBLE (2500 4475);
FORCEPROP 1 LAST PACK_TYPE SSOPLF
J 0
(2500 4325);
DISPLAY 0.978723 (2500 4325);
PAINT SKYBLUE (2500 4325);
DISPLAY INVISIBLE (2500 4325);
FORCEPROP 0 LAST CDS_SEC 2
J 0
(2500 4325);
PAINT MONO (2500 4325);
DISPLAY INVISIBLE (2500 4325);
FORCEPROP 1 LAST PATH I46
J 0
(2900 4175);
DISPLAY 0.978723 (2900 4175);
PAINT BLUE (2900 4175);
DISPLAY INVISIBLE (2900 4175);
FORCEPROP 2 LAST CDS_LOCATION Q8D1
J 0
(2500 4275);
DISPLAY 0.617021 (2500 4275);
PAINT AQUA (2500 4275);
DISPLAY INVISIBLE (2500 4275);
FORCEADD GND..1
(2200 2275);
FORCEPROP 3 LASTPIN (2200 2325) SIG_NAME GND\g
J 0
(2210 2335);
DISPLAY 0.659574 (2210 2335);
PAINT MONO (2210 2335);
DISPLAY INVISIBLE (2210 2335);
FORCEPROP 1 LAST PATH I47
J 0
(2275 2275);
DISPLAY 0.872340 (2275 2275);
PAINT AQUA (2275 2275);
DISPLAY INVISIBLE (2275 2275);
FORCEPROP 1 LAST SIZE 1B
J 0
(2275 2225);
DISPLAY 0.872340 (2275 2225);
PAINT AQUA (2275 2225);
DISPLAY INVISIBLE (2275 2225);
FORCEPROP 1 LAST VOLTAGE 0.0V
J 0
(2155 2232);
DISPLAY 0.340426 (2155 2232);
PAINT SKYBLUE (2155 2232);
DISPLAY INVISIBLE (2155 2232);
FORCEPROP 2 LAST CDS_LIB mstr_symbols
J 0
(2200 2275);
PAINT MONO (2200 2275);
DISPLAY INVISIBLE (2200 2275);
FORCEPROP 1 LAST BODY_TYPE PLUMBING
J 0
(2155 2232);
DISPLAY 0.340426 (2155 2232);
PAINT GREEN (2155 2232);
DISPLAY INVISIBLE (2155 2232);
FORCEPROP 1 LAST HDL_POWER GND
J 0
(2200 2425);
DISPLAY 0.872340 (2200 2425);
PAINT GREEN (2200 2425);
DISPLAY INVISIBLE (2200 2425);
FORCEADD GND..1
(2950 2750);
FORCEPROP 3 LASTPIN (2950 2800) SIG_NAME GND\g
J 0
(2960 2810);
DISPLAY 0.659574 (2960 2810);
PAINT MONO (2960 2810);
DISPLAY INVISIBLE (2960 2810);
FORCEPROP 1 LAST PATH I48
J 0
(3025 2750);
DISPLAY 0.872340 (3025 2750);
PAINT AQUA (3025 2750);
DISPLAY INVISIBLE (3025 2750);
FORCEPROP 1 LAST SIZE 1B
J 0
(3025 2700);
DISPLAY 0.872340 (3025 2700);
PAINT AQUA (3025 2700);
DISPLAY INVISIBLE (3025 2700);
FORCEPROP 2 LAST CDS_LIB mstr_symbols
J 0
(2950 2750);
PAINT MONO (2950 2750);
DISPLAY INVISIBLE (2950 2750);
FORCEPROP 1 LAST VOLTAGE 0.0V
J 0
(2905 2707);
DISPLAY 0.340426 (2905 2707);
PAINT SKYBLUE (2905 2707);
DISPLAY INVISIBLE (2905 2707);
FORCEPROP 1 LAST BODY_TYPE PLUMBING
J 0
(2905 2707);
DISPLAY 0.340426 (2905 2707);
PAINT GREEN (2905 2707);
DISPLAY INVISIBLE (2905 2707);
FORCEPROP 1 LAST HDL_POWER GND
J 0
(2950 2900);
DISPLAY 0.872340 (2950 2900);
PAINT GREEN (2950 2900);
DISPLAY INVISIBLE (2950 2900);
FORCEADD RES..2
(2200 3250);
FORCEPROP 1 LAST LOCATION R8W9
J 0
(2070 3325);
DISPLAY 0.617021 (2070 3325);
PAINT AQUA (2070 3325);
FORCEPROP 1 LAST MATERIAL CHIP
J 0
(2240 3175);
DISPLAY 0.617021 (2240 3175);
PAINT SKYBLUE (2240 3175);
FORCEPROP 1 LAST PACK_TYPE 0402
J 0
(2240 3075);
DISPLAY 0.617021 (2240 3075);
PAINT SKYBLUE (2240 3075);
FORCEPROP 1 LASTPIN (2200 3150) $PN 2
J 0
(2205 3160);
DISPLAY 0.787234 (2205 3160);
PAINT ORANGE (2205 3160);
FORCEPROP 1 LAST PART_NUMBER G21796-072
J 0
(2240 3125);
DISPLAY 0.617021 (2240 3125);
PAINT BLUE (2240 3125);
FORCEPROP 1 LAST TOLERANCE 1%
J 0
(2245 3275);
DISPLAY 0.617021 (2245 3275);
PAINT SKYBLUE (2245 3275);
FORCEPROP 1 LAST WATTAGE 1/16W
J 0
(2240 3225);
DISPLAY 0.617021 (2240 3225);
PAINT SKYBLUE (2240 3225);
FORCEPROP 1 LASTPIN (2200 3350) $PN 1
J 0
(2205 3312);
DISPLAY 0.787234 (2205 3312);
PAINT ORANGE (2205 3312);
FORCEPROP 1 LAST VALUE 4.75K
J 0
(2245 3325);
DISPLAY 0.617021 (2245 3325);
PAINT SKYBLUE (2245 3325);
FORCEPROP 0 LAST ROOM NVDIMM
J 0
(2250 3475);
DISPLAY 1.021277 (2250 3475);
PAINT ORANGE (2250 3475);
DISPLAY INVISIBLE (2250 3475);
FORCEPROP 2 LAST CDS_LIB mstr_discrete
J 0
(2200 3250);
PAINT MONO (2200 3250);
DISPLAY INVISIBLE (2200 3250);
FORCEPROP 1 LAST PATH I49
J 0
(2250 3425);
DISPLAY 0.978723 (2250 3425);
PAINT WHITE (2250 3425);
DISPLAY INVISIBLE (2250 3425);
FORCEPROP 2 LAST SEC_TYPE 0402
J 0
(2250 3475);
DISPLAY 1.021277 (2250 3475);
PAINT ORANGE (2250 3475);
DISPLAY INVISIBLE (2250 3475);
FORCEPROP 2 LAST SEC 1
J 0
(2250 3475);
PAINT MONO (2250 3475);
DISPLAY INVISIBLE (2250 3475);
FORCEPROP 2 LAST CDS_LOCATION R8W9
J 0
(2245 3375);
DISPLAY 0.617021 (2245 3375);
PAINT AQUA (2245 3375);
DISPLAY INVISIBLE (2245 3375);
FORCEADD RES..1
(350 1950);
FORCEPROP 1 LAST PACK_TYPE 0402
J 0
(600 1800);
DISPLAY 0.617021 (600 1800);
PAINT SKYBLUE (600 1800);
FORCEPROP 1 LAST PART_NUMBER G21796-047
J 0
(300 2050);
DISPLAY 0.617021 (300 2050);
PAINT BLUE (300 2050);
FORCEPROP 1 LAST VALUE 49.9
J 2
(325 1850);
DISPLAY 0.617021 (325 1850);
PAINT SKYBLUE (325 1850);
FORCEPROP 1 LASTPIN (450 1950) $PN 2
J 0
(412 1962);
DISPLAY 0.617021 (412 1962);
PAINT ORANGE (412 1962);
FORCEPROP 1 LASTPIN (250 1950) $PN 1
J 0
(262 1962);
DISPLAY 0.617021 (262 1962);
PAINT ORANGE (262 1962);
FORCEPROP 1 LAST LOCATION R6F5
J 0
(300 2000);
DISPLAY 0.617021 (300 2000);
PAINT AQUA (300 2000);
FORCEPROP 1 LAST TOLERANCE 1%
J 0
(350 1850);
DISPLAY 0.617021 (350 1850);
PAINT SKYBLUE (350 1850);
FORCEPROP 1 LAST MATERIAL CHIP
J 0
(350 1800);
DISPLAY 0.617021 (350 1800);
PAINT SKYBLUE (350 1800);
FORCEPROP 1 LAST WATTAGE 1/16W
J 2
(325 1800);
DISPLAY 0.617021 (325 1800);
PAINT SKYBLUE (325 1800);
FORCEPROP 2 LAST CDS_LIB mstr_discrete
J 0
(350 1950);
PAINT ORANGE (350 1950);
DISPLAY INVISIBLE (350 1950);
FORCEPROP 2 LAST CDS_LOCATION R6F5
J 0
(300 2000);
DISPLAY 0.617021 (300 2000);
PAINT AQUA (300 2000);
DISPLAY INVISIBLE (300 2000);
FORCEPROP 0 LAST ROOM NV_DIMM
J 0
(300 2100);
DISPLAY 1.021277 (300 2100);
PAINT ORANGE (300 2100);
DISPLAY INVISIBLE (300 2100);
FORCEPROP 1 LAST PATH I5
J 0
(300 2100);
DISPLAY 0.978723 (300 2100);
PAINT WHITE (300 2100);
DISPLAY INVISIBLE (300 2100);
FORCEPROP 0 LAST SEC 1
J 0
(300 2100);
DISPLAY 0.680851 (300 2100);
PAINT MONO (300 2100);
DISPLAY INVISIBLE (300 2100);
FORCEPROP 0 LAST BOM_COST MEM_NV
J 0
(300 2150);
DISPLAY 1.021277 (300 2150);
PAINT ORANGE (300 2150);
DISPLAY INVISIBLE (300 2150);
FORCEPROP 2 LAST SEC_TYPE 0402
J 0
(300 2150);
DISPLAY 1.021277 (300 2150);
PAINT ORANGE (300 2150);
DISPLAY INVISIBLE (300 2150);
FORCEADD P3V3_STBY..1
(2200 3525);
FORCEPROP 3 LASTPIN (2200 3475) SIG_NAME P3V3_STBY\g
J 0
(2210 3485);
DISPLAY 0.659574 (2210 3485);
PAINT MONO (2210 3485);
DISPLAY INVISIBLE (2210 3485);
FORCEPROP 2 LAST CDS_LIB mstr_symbols
J 0
(2200 3525);
PAINT MONO (2200 3525);
DISPLAY INVISIBLE (2200 3525);
FORCEPROP 1 LAST SIZE 1B
J 0
(2245 3547);
DISPLAY 0.340426 (2245 3547);
PAINT GREEN (2245 3547);
DISPLAY INVISIBLE (2245 3547);
FORCEPROP 1 LAST VOLTAGE 3.3V
J 0
(2155 3482);
DISPLAY 0.340426 (2155 3482);
PAINT SKYBLUE (2155 3482);
DISPLAY INVISIBLE (2155 3482);
FORCEPROP 1 LAST PATH I50
J 0
(2245 3527);
DISPLAY 0.340426 (2245 3527);
PAINT GREEN (2245 3527);
DISPLAY INVISIBLE (2245 3527);
FORCEPROP 1 LAST BODY_TYPE PLUMBING
J 0
(2155 3482);
DISPLAY 0.340426 (2155 3482);
PAINT GREEN (2155 3482);
DISPLAY INVISIBLE (2155 3482);
FORCEPROP 1 LAST HDL_POWER P3V3_STBY
J 0
(1900 3400);
DISPLAY 0.872340 (1900 3400);
PAINT ORANGE (1900 3400);
DISPLAY INVISIBLE (1900 3400);
FORCEADD NPN_DUAL..1
(2900 2975);
FORCEPROP 1 LAST VALUE MBT3904
J 0
(3000 3025);
DISPLAY 0.617021 (3000 3025);
PAINT SKYBLUE (3000 3025);
FORCEPROP 1 LASTPIN (2950 2875) $PN 1
J 2
(2940 2875);
DISPLAY 0.617021 (2940 2875);
PAINT AQUA (2940 2875);
FORCEPROP 1 LASTPIN (2800 2975) $PN 2
J 0
(2815 2980);
DISPLAY 0.617021 (2815 2980);
PAINT AQUA (2815 2980);
FORCEPROP 1 LAST LOCATION Q8W1
J 0
(3000 3075);
DISPLAY 0.617021 (3000 3075);
PAINT AQUA (3000 3075);
FORCEPROP 1 LASTPIN (2950 3075) $PN 6
J 0
(2890 3035);
DISPLAY 0.617021 (2890 3035);
PAINT AQUA (2890 3035);
FORCEPROP 1 LAST MATERIAL XSTR
J 0
(3000 2975);
DISPLAY 0.617021 (3000 2975);
PAINT SKYBLUE (3000 2975);
FORCEPROP 1 LAST PART_NUMBER C52264-001
J 0
(3000 2925);
DISPLAY 0.617021 (3000 2925);
PAINT BLUE (3000 2925);
FORCEPROP 1 LAST PATH I51
J 0
(3400 2975);
DISPLAY 0.978723 (3400 2975);
PAINT BLUE (3400 2975);
DISPLAY INVISIBLE (3400 2975);
FORCEPROP 2 LAST CDS_LIB mstr_discrete
J 0
(2900 2975);
PAINT ORANGE (2900 2975);
DISPLAY INVISIBLE (2900 2975);
FORCEPROP 0 LAST ROOM NV_DIMM
J 0
(3000 3175);
DISPLAY 1.021277 (3000 3175);
PAINT ORANGE (3000 3175);
DISPLAY INVISIBLE (3000 3175);
FORCEPROP 2 LAST SEC 2
J 0
(3000 3125);
DISPLAY 0.680851 (3000 3125);
PAINT MONO (3000 3125);
DISPLAY INVISIBLE (3000 3125);
FORCEPROP 2 LAST SEC_TYPE SSOPLF
J 0
(3000 3125);
DISPLAY 1.021277 (3000 3125);
PAINT ORANGE (3000 3125);
DISPLAY INVISIBLE (3000 3125);
FORCEPROP 0 LAST BOM_COST MEM_NV
J 0
(3000 3275);
DISPLAY 1.021277 (3000 3275);
PAINT ORANGE (3000 3275);
DISPLAY INVISIBLE (3000 3275);
FORCEPROP 1 LAST PACK_TYPE SSOPLF
J 0
(3000 3125);
DISPLAY 0.978723 (3000 3125);
PAINT SKYBLUE (3000 3125);
DISPLAY INVISIBLE (3000 3125);
FORCEPROP 0 LAST CDS_SEC 2
J 0
(3000 3125);
PAINT MONO (3000 3125);
DISPLAY INVISIBLE (3000 3125);
FORCEPROP 2 LAST CDS_LOCATION Q8W1
J 0
(3000 3075);
DISPLAY 0.617021 (3000 3075);
PAINT AQUA (3000 3075);
DISPLAY INVISIBLE (3000 3075);
FORCEADD NPN_DUAL..1
(2150 2500);
FORCEPROP 1 LASTPIN (2050 2500) $PN 5
J 0
(2065 2505);
DISPLAY 0.617021 (2065 2505);
PAINT AQUA (2065 2505);
FORCEPROP 1 LASTPIN (2200 2400) $PN 4
J 2
(2190 2400);
DISPLAY 0.617021 (2190 2400);
PAINT AQUA (2190 2400);
FORCEPROP 1 LAST LOCATION Q8W1
J 0
(2250 2600);
DISPLAY 0.617021 (2250 2600);
PAINT AQUA (2250 2600);
FORCEPROP 1 LAST MATERIAL XSTR
J 0
(2250 2500);
DISPLAY 0.617021 (2250 2500);
PAINT SKYBLUE (2250 2500);
FORCEPROP 1 LAST VALUE MBT3904
J 0
(2250 2550);
DISPLAY 0.617021 (2250 2550);
PAINT SKYBLUE (2250 2550);
FORCEPROP 1 LASTPIN (2200 2600) $PN 3
J 0
(2140 2560);
DISPLAY 0.617021 (2140 2560);
PAINT AQUA (2140 2560);
FORCEPROP 1 LAST PART_NUMBER C52264-001
J 0
(2250 2450);
DISPLAY 0.617021 (2250 2450);
PAINT BLUE (2250 2450);
FORCEPROP 1 LAST PATH I52
J 0
(2650 2500);
DISPLAY 0.978723 (2650 2500);
PAINT BLUE (2650 2500);
DISPLAY INVISIBLE (2650 2500);
FORCEPROP 0 LAST ROOM NV_DIMM
J 0
(2250 2700);
DISPLAY 1.021277 (2250 2700);
PAINT ORANGE (2250 2700);
DISPLAY INVISIBLE (2250 2700);
FORCEPROP 2 LAST SEC 1
J 0
(2250 2650);
DISPLAY 0.680851 (2250 2650);
PAINT MONO (2250 2650);
DISPLAY INVISIBLE (2250 2650);
FORCEPROP 2 LAST CDS_LIB mstr_discrete
J 0
(2150 2500);
PAINT ORANGE (2150 2500);
DISPLAY INVISIBLE (2150 2500);
FORCEPROP 2 LAST SEC_TYPE SSOPLF
J 0
(2250 2650);
DISPLAY 1.021277 (2250 2650);
PAINT ORANGE (2250 2650);
DISPLAY INVISIBLE (2250 2650);
FORCEPROP 0 LAST BOM_COST MEM_NV
J 0
(2250 2700);
DISPLAY 1.021277 (2250 2700);
PAINT ORANGE (2250 2700);
DISPLAY INVISIBLE (2250 2700);
FORCEPROP 1 LAST PACK_TYPE SSOPLF
J 0
(2250 2650);
DISPLAY 0.978723 (2250 2650);
PAINT SKYBLUE (2250 2650);
DISPLAY INVISIBLE (2250 2650);
FORCEPROP 2 LAST CDS_LOCATION Q8W1
J 0
(2250 2600);
DISPLAY 0.617021 (2250 2600);
PAINT AQUA (2250 2600);
DISPLAY INVISIBLE (2250 2600);
FORCEADD NPN..1
(-500 2725);
FORCEPROP 1 LAST PART_NUMBER C52245-001
J 0
(-350 2575);
DISPLAY 0.617021 (-350 2575);
PAINT BLUE (-350 2575);
FORCEPROP 1 LASTPIN (-450 2625) $PN 2
J 0
(-425 2575);
DISPLAY 0.617021 (-425 2575);
PAINT GREEN (-425 2575);
FORCEPROP 1 LAST MATERIAL IC
J 0
(-350 2675);
DISPLAY 0.617021 (-350 2675);
PAINT SKYBLUE (-350 2675);
FORCEPROP 1 LAST PACK_TYPE SM
J 0
(-350 2625);
DISPLAY 0.617021 (-350 2625);
PAINT SKYBLUE (-350 2625);
FORCEPROP 1 LASTPIN (-450 2825) $PN 3
J 0
(-431 2835);
DISPLAY 0.617021 (-431 2835);
PAINT GREEN (-431 2835);
FORCEPROP 1 LASTPIN (-600 2725) $PN 1
J 0
(-630 2800);
DISPLAY 0.617021 (-630 2800);
PAINT GREEN (-630 2800);
FORCEPROP 1 LAST LOCATION Q1F1
J 0
(-350 2775);
DISPLAY 0.617021 (-350 2775);
PAINT AQUA (-350 2775);
FORCEPROP 1 LAST VALUE MMBT3904
J 0
(-350 2725);
DISPLAY 0.617021 (-350 2725);
PAINT SKYBLUE (-350 2725);
FORCEPROP 0 LAST CDS_SEC 1
J 0
(-350 2825);
PAINT MONO (-350 2825);
DISPLAY INVISIBLE (-350 2825);
FORCEPROP 0 LAST BOM_COST PROC_SIDEBAND
J 0
(-350 2975);
DISPLAY 1.021277 (-350 2975);
PAINT ORANGE (-350 2975);
DISPLAY INVISIBLE (-350 2975);
FORCEPROP 2 LAST SEC_TYPE SM
J 0
(-350 2875);
DISPLAY 1.021277 (-350 2875);
PAINT ORANGE (-350 2875);
DISPLAY INVISIBLE (-350 2875);
FORCEPROP 2 LAST SEC 1
J 0
(-350 2875);
DISPLAY 0.680851 (-350 2875);
PAINT MONO (-350 2875);
DISPLAY INVISIBLE (-350 2875);
FORCEPROP 0 LAST ROOM PROC_SIDEBAND
J 0
(-350 2875);
DISPLAY 1.021277 (-350 2875);
PAINT ORANGE (-350 2875);
DISPLAY INVISIBLE (-350 2875);
FORCEPROP 2 LAST CDS_LIB mstr_discrete
J 0
(-500 2725);
PAINT MONO (-500 2725);
DISPLAY INVISIBLE (-500 2725);
FORCEPROP 1 LAST PATH I53
J 0
(-350 2825);
DISPLAY 0.978723 (-350 2825);
PAINT BLUE (-350 2825);
DISPLAY INVISIBLE (-350 2825);
FORCEPROP 2 LAST CDS_LOCATION Q1F1
J 0
(-350 2775);
DISPLAY 0.617021 (-350 2775);
PAINT AQUA (-350 2775);
DISPLAY INVISIBLE (-350 2775);
FORCEADD RES..1
(-1350 2725);
FORCEPROP 1 LASTPIN (-1250 2725) $PN 2
J 0
(-1288 2737);
DISPLAY 0.617021 (-1288 2737);
PAINT ORANGE (-1288 2737);
FORCEPROP 1 LASTPIN (-1450 2725) $PN 1
J 0
(-1438 2737);
DISPLAY 0.617021 (-1438 2737);
PAINT ORANGE (-1438 2737);
FORCEPROP 1 LAST WATTAGE 1/16W
J 2
(-1375 2575);
DISPLAY 0.617021 (-1375 2575);
PAINT SKYBLUE (-1375 2575);
FORCEPROP 1 LAST VALUE 330
J 2
(-1375 2625);
DISPLAY 0.617021 (-1375 2625);
PAINT SKYBLUE (-1375 2625);
FORCEPROP 1 LAST TOLERANCE 5%
J 0
(-1350 2625);
DISPLAY 0.617021 (-1350 2625);
PAINT SKYBLUE (-1350 2625);
FORCEPROP 1 LAST MATERIAL CHIP
J 0
(-1350 2575);
DISPLAY 0.617021 (-1350 2575);
PAINT SKYBLUE (-1350 2575);
FORCEPROP 1 LAST LOCATION R1W32
J 0
(-1400 2775);
DISPLAY 0.617021 (-1400 2775);
PAINT AQUA (-1400 2775);
FORCEPROP 1 LAST PART_NUMBER G21497-028
J 0
(-1400 2825);
DISPLAY 0.617021 (-1400 2825);
PAINT BLUE (-1400 2825);
FORCEPROP 1 LAST PACK_TYPE 0402
J 0
(-1250 2575);
DISPLAY 0.617021 (-1250 2575);
PAINT SKYBLUE (-1250 2575);
FORCEPROP 1 LAST PATH I54
J 0
(-1400 2875);
DISPLAY 0.978723 (-1400 2875);
PAINT WHITE (-1400 2875);
DISPLAY INVISIBLE (-1400 2875);
FORCEPROP 2 LAST ROOM UART_MUX
J 0
(-1400 2875);
DISPLAY 1.021277 (-1400 2875);
PAINT ORANGE (-1400 2875);
DISPLAY INVISIBLE (-1400 2875);
FORCEPROP 2 LAST BOM_COST DEBUG
J 0
(-1400 2925);
DISPLAY 1.021277 (-1400 2925);
PAINT ORANGE (-1400 2925);
DISPLAY INVISIBLE (-1400 2925);
FORCEPROP 2 LAST SEC_TYPE 0402
J 0
(-1400 2925);
DISPLAY 1.021277 (-1400 2925);
PAINT ORANGE (-1400 2925);
DISPLAY INVISIBLE (-1400 2925);
FORCEPROP 2 LAST CDS_LIB mstr_discrete
J 0
(-1350 2725);
PAINT ORANGE (-1350 2725);
DISPLAY INVISIBLE (-1350 2725);
FORCEPROP 2 LAST SEC 1
J 0
(-1400 2925);
DISPLAY 0.680851 (-1400 2925);
PAINT MONO (-1400 2925);
DISPLAY INVISIBLE (-1400 2925);
FORCEPROP 2 LAST CDS_LOCATION R1W32
J 0
(-1400 2775);
DISPLAY 0.617021 (-1400 2775);
PAINT AQUA (-1400 2775);
DISPLAY INVISIBLE (-1400 2775);
FORCEADD NPN..1
(-500 1550);
FORCEPROP 1 LAST PACK_TYPE SM
J 0
(-350 1450);
DISPLAY 0.617021 (-350 1450);
PAINT SKYBLUE (-350 1450);
FORCEPROP 1 LAST VALUE MMBT3904
J 0
(-350 1550);
DISPLAY 0.617021 (-350 1550);
PAINT SKYBLUE (-350 1550);
FORCEPROP 1 LAST PART_NUMBER C52245-001
J 0
(-350 1400);
DISPLAY 0.617021 (-350 1400);
PAINT BLUE (-350 1400);
FORCEPROP 1 LAST LOCATION Q1W6
J 0
(-350 1600);
DISPLAY 0.617021 (-350 1600);
PAINT AQUA (-350 1600);
FORCEPROP 1 LASTPIN (-450 1450) $PN 2
J 0
(-425 1400);
DISPLAY 0.617021 (-425 1400);
PAINT GREEN (-425 1400);
FORCEPROP 1 LASTPIN (-450 1650) $PN 3
J 0
(-431 1660);
DISPLAY 0.617021 (-431 1660);
PAINT GREEN (-431 1660);
FORCEPROP 1 LAST MATERIAL IC
J 0
(-350 1500);
DISPLAY 0.617021 (-350 1500);
PAINT SKYBLUE (-350 1500);
FORCEPROP 1 LASTPIN (-600 1550) $PN 1
J 0
(-630 1625);
DISPLAY 0.617021 (-630 1625);
PAINT GREEN (-630 1625);
FORCEPROP 2 LAST CDS_LIB mstr_discrete
J 0
(-500 1550);
PAINT MONO (-500 1550);
DISPLAY INVISIBLE (-500 1550);
FORCEPROP 0 LAST ROOM PROC_SIDEBAND
J 0
(-350 1700);
DISPLAY 1.021277 (-350 1700);
PAINT ORANGE (-350 1700);
DISPLAY INVISIBLE (-350 1700);
FORCEPROP 2 LAST SEC 1
J 0
(-350 1700);
DISPLAY 0.680851 (-350 1700);
PAINT MONO (-350 1700);
DISPLAY INVISIBLE (-350 1700);
FORCEPROP 2 LAST SEC_TYPE SM
J 0
(-350 1700);
DISPLAY 1.021277 (-350 1700);
PAINT ORANGE (-350 1700);
DISPLAY INVISIBLE (-350 1700);
FORCEPROP 0 LAST BOM_COST PROC_SIDEBAND
J 0
(-350 1800);
DISPLAY 1.021277 (-350 1800);
PAINT ORANGE (-350 1800);
DISPLAY INVISIBLE (-350 1800);
FORCEPROP 0 LAST CDS_SEC 1
J 0
(-350 1650);
PAINT MONO (-350 1650);
DISPLAY INVISIBLE (-350 1650);
FORCEPROP 1 LAST PATH I55
J 0
(-350 1650);
DISPLAY 0.978723 (-350 1650);
PAINT BLUE (-350 1650);
DISPLAY INVISIBLE (-350 1650);
FORCEPROP 2 LAST CDS_LOCATION Q1W6
J 0
(-350 1600);
DISPLAY 0.617021 (-350 1600);
PAINT AQUA (-350 1600);
DISPLAY INVISIBLE (-350 1600);
FORCEADD RES..1
(-1350 1550);
FORCEPROP 1 LAST WATTAGE 1/16W
J 2
(-1375 1400);
DISPLAY 0.617021 (-1375 1400);
PAINT SKYBLUE (-1375 1400);
FORCEPROP 1 LAST PACK_TYPE 0402
J 0
(-1250 1400);
DISPLAY 0.617021 (-1250 1400);
PAINT SKYBLUE (-1250 1400);
FORCEPROP 1 LAST MATERIAL CHIP
J 0
(-1350 1400);
DISPLAY 0.617021 (-1350 1400);
PAINT SKYBLUE (-1350 1400);
FORCEPROP 1 LASTPIN (-1450 1550) $PN 1
J 0
(-1438 1562);
DISPLAY 0.617021 (-1438 1562);
PAINT ORANGE (-1438 1562);
FORCEPROP 1 LASTPIN (-1250 1550) $PN 2
J 0
(-1288 1562);
DISPLAY 0.617021 (-1288 1562);
PAINT ORANGE (-1288 1562);
FORCEPROP 1 LAST LOCATION R1W31
J 0
(-1400 1600);
DISPLAY 0.617021 (-1400 1600);
PAINT AQUA (-1400 1600);
FORCEPROP 1 LAST VALUE 330
J 2
(-1375 1450);
DISPLAY 0.617021 (-1375 1450);
PAINT SKYBLUE (-1375 1450);
FORCEPROP 1 LAST TOLERANCE 5%
J 0
(-1350 1450);
DISPLAY 0.617021 (-1350 1450);
PAINT SKYBLUE (-1350 1450);
FORCEPROP 1 LAST PART_NUMBER G21497-028
J 0
(-1400 1650);
DISPLAY 0.617021 (-1400 1650);
PAINT BLUE (-1400 1650);
FORCEPROP 2 LAST SEC 1
J 0
(-1400 1750);
DISPLAY 0.680851 (-1400 1750);
PAINT MONO (-1400 1750);
DISPLAY INVISIBLE (-1400 1750);
FORCEPROP 2 LAST CDS_LIB mstr_discrete
J 0
(-1350 1550);
PAINT ORANGE (-1350 1550);
DISPLAY INVISIBLE (-1350 1550);
FORCEPROP 2 LAST SEC_TYPE 0402
J 0
(-1400 1750);
DISPLAY 1.021277 (-1400 1750);
PAINT ORANGE (-1400 1750);
DISPLAY INVISIBLE (-1400 1750);
FORCEPROP 2 LAST BOM_COST DEBUG
J 0
(-1400 1750);
DISPLAY 1.021277 (-1400 1750);
PAINT ORANGE (-1400 1750);
DISPLAY INVISIBLE (-1400 1750);
FORCEPROP 2 LAST ROOM UART_MUX
J 0
(-1400 1700);
DISPLAY 1.021277 (-1400 1700);
PAINT ORANGE (-1400 1700);
DISPLAY INVISIBLE (-1400 1700);
FORCEPROP 1 LAST PATH I56
J 0
(-1400 1700);
DISPLAY 0.978723 (-1400 1700);
PAINT WHITE (-1400 1700);
DISPLAY INVISIBLE (-1400 1700);
FORCEPROP 2 LAST CDS_LOCATION R1W31
J 0
(-1400 1600);
DISPLAY 0.617021 (-1400 1600);
PAINT AQUA (-1400 1600);
DISPLAY INVISIBLE (-1400 1600);
FORCEADD RES..1
(350 1650);
FORCEPROP 1 LAST VALUE 49.9
J 2
(325 1550);
DISPLAY 0.617021 (325 1550);
PAINT SKYBLUE (325 1550);
FORCEPROP 1 LAST PACK_TYPE 0402
J 0
(600 1500);
DISPLAY 0.617021 (600 1500);
PAINT SKYBLUE (600 1500);
FORCEPROP 1 LAST TOLERANCE 1%
J 0
(350 1550);
DISPLAY 0.617021 (350 1550);
PAINT SKYBLUE (350 1550);
FORCEPROP 1 LAST MATERIAL CHIP
J 0
(350 1500);
DISPLAY 0.617021 (350 1500);
PAINT SKYBLUE (350 1500);
FORCEPROP 1 LAST WATTAGE 1/16W
J 2
(325 1500);
DISPLAY 0.617021 (325 1500);
PAINT SKYBLUE (325 1500);
FORCEPROP 1 LAST PART_NUMBER G21796-047
J 0
(300 1750);
DISPLAY 0.617021 (300 1750);
PAINT BLUE (300 1750);
FORCEPROP 1 LASTPIN (450 1650) $PN 2
J 0
(412 1662);
DISPLAY 0.617021 (412 1662);
PAINT ORANGE (412 1662);
FORCEPROP 1 LASTPIN (250 1650) $PN 1
J 0
(262 1662);
DISPLAY 0.617021 (262 1662);
PAINT ORANGE (262 1662);
FORCEPROP 1 LAST LOCATION R6F2
J 0
(300 1700);
DISPLAY 0.617021 (300 1700);
PAINT AQUA (300 1700);
FORCEPROP 2 LAST CDS_LIB mstr_discrete
J 0
(350 1650);
PAINT ORANGE (350 1650);
DISPLAY INVISIBLE (350 1650);
FORCEPROP 0 LAST SEC 1
J 0
(300 1800);
DISPLAY 0.680851 (300 1800);
PAINT MONO (300 1800);
DISPLAY INVISIBLE (300 1800);
FORCEPROP 2 LAST CDS_LOCATION R6F2
J 0
(300 1700);
DISPLAY 0.617021 (300 1700);
PAINT AQUA (300 1700);
DISPLAY INVISIBLE (300 1700);
FORCEPROP 1 LAST PATH I6
J 0
(300 1800);
DISPLAY 0.978723 (300 1800);
PAINT WHITE (300 1800);
DISPLAY INVISIBLE (300 1800);
FORCEPROP 0 LAST ROOM NV_DIMM
J 0
(300 1800);
DISPLAY 1.021277 (300 1800);
PAINT ORANGE (300 1800);
DISPLAY INVISIBLE (300 1800);
FORCEPROP 0 LAST BOM_COST MEM_NV
J 0
(300 1850);
DISPLAY 1.021277 (300 1850);
PAINT ORANGE (300 1850);
DISPLAY INVISIBLE (300 1850);
FORCEPROP 2 LAST SEC_TYPE 0402
J 0
(300 1850);
DISPLAY 1.021277 (300 1850);
PAINT ORANGE (300 1850);
DISPLAY INVISIBLE (300 1850);
FORCEADD RES..2
(-450 3325);
FORCEPROP 1 LAST LOCATION R6F3
J 0
(-405 3450);
DISPLAY 0.617021 (-405 3450);
PAINT AQUA (-405 3450);
FORCEPROP 1 LAST VALUE 10.0K
J 0
(-405 3400);
DISPLAY 0.617021 (-405 3400);
PAINT SKYBLUE (-405 3400);
FORCEPROP 1 LAST TOLERANCE 1%
J 0
(-405 3350);
DISPLAY 0.617021 (-405 3350);
PAINT SKYBLUE (-405 3350);
FORCEPROP 1 LAST WATTAGE 1/16W
J 0
(-410 3300);
DISPLAY 0.617021 (-410 3300);
PAINT SKYBLUE (-410 3300);
FORCEPROP 1 LAST MATERIAL CHIP
J 0
(-410 3250);
DISPLAY 0.617021 (-410 3250);
PAINT SKYBLUE (-410 3250);
FORCEPROP 1 LAST PACK_TYPE 0402
J 0
(-410 3150);
DISPLAY 0.617021 (-410 3150);
PAINT SKYBLUE (-410 3150);
FORCEPROP 1 LASTPIN (-450 3425) $PN 1
J 0
(-445 3387);
DISPLAY 0.617021 (-445 3387);
PAINT ORANGE (-445 3387);
FORCEPROP 1 LASTPIN (-450 3225) $PN 2
J 0
(-445 3235);
DISPLAY 0.617021 (-445 3235);
PAINT ORANGE (-445 3235);
FORCEPROP 1 LAST PART_NUMBER G21796-016
J 0
(-410 3200);
DISPLAY 0.617021 (-410 3200);
PAINT BLUE (-410 3200);
FORCEPROP 0 LAST SEC 1
J 0
(-400 3500);
DISPLAY 0.680851 (-400 3500);
PAINT MONO (-400 3500);
DISPLAY INVISIBLE (-400 3500);
FORCEPROP 2 LAST SEC_TYPE 0402
J 0
(-400 3550);
DISPLAY 1.021277 (-400 3550);
PAINT ORANGE (-400 3550);
DISPLAY INVISIBLE (-400 3550);
FORCEPROP 0 LAST BOM_COST MEM_NV
J 0
(-400 3550);
DISPLAY 1.021277 (-400 3550);
PAINT ORANGE (-400 3550);
DISPLAY INVISIBLE (-400 3550);
FORCEPROP 0 LAST ROOM NV_DIMM
J 0
(-400 3500);
DISPLAY 1.021277 (-400 3500);
PAINT ORANGE (-400 3500);
DISPLAY INVISIBLE (-400 3500);
FORCEPROP 2 LAST CDS_LOCATION R6F3
J 0
(-405 3450);
DISPLAY 0.617021 (-405 3450);
PAINT AQUA (-405 3450);
DISPLAY INVISIBLE (-405 3450);
FORCEPROP 2 LAST CDS_LIB mstr_discrete
J 0
(-450 3325);
PAINT ORANGE (-450 3325);
DISPLAY INVISIBLE (-450 3325);
FORCEPROP 1 LAST PATH I7
J 0
(-400 3500);
DISPLAY 0.978723 (-400 3500);
PAINT WHITE (-400 3500);
DISPLAY INVISIBLE (-400 3500);
FORCEADD OFFPAGE..1
(-2875 3025);
FORCEPROP 2 LASTPIN (-2825 3025) SIG_NAME FM_ADR_COMPLETE
J 0
(-2835 3035);
DISPLAY 0.617021 (-2835 3035);
PAINT ORANGE (-2835 3035);
FORCEPROP 2 LAST $XR1 191 
J 0
(-3247 3025);
DISPLAY 0.638298 (-3247 3025);
PAINT MONO (-3247 3025);
FORCEPROP 2 LAST $XR0 120 
J 0
(-3127 3025);
DISPLAY 0.638298 (-3127 3025);
PAINT MONO (-3127 3025);
FORCEPROP 2 LAST PATH I9
J 0
(-2825 3100);
DISPLAY 1.021277 (-2825 3100);
PAINT ORANGE (-2825 3100);
DISPLAY INVISIBLE (-2825 3100);
FORCEPROP 2 LAST CDS_LIB mstr_standard
J 0
(-2875 3025);
PAINT ORANGE (-2875 3025);
DISPLAY INVISIBLE (-2875 3025);
FORCEPROP 1 LAST OFFPAGE TRUE
J 0
(-2550 2900);
DISPLAY 0.872340 (-2550 2900);
PAINT GREEN (-2550 2900);
DISPLAY INVISIBLE (-2550 2900);
FORCEPROP 1 LAST COMMENT_BODY TRUE
J 0
(-2750 2925);
DISPLAY 0.872340 (-2750 2925);
PAINT GREEN (-2750 2925);
DISPLAY INVISIBLE (-2750 2925);
FORCEADD DNS..2
(-2245 3020);
PAINT RED (-2245 3020);
FORCEPROP 2 LAST CDS_LIB mstr_misc
J 0
(-2245 3020);
PAINT ORANGE (-2245 3020);
DISPLAY INVISIBLE (-2245 3020);
FORCEPROP 1 LAST COMMENT_BODY TRUE
R 1
J 0
(-2170 2795);
DISPLAY 0.872340 (-2170 2795);
PAINT GREEN (-2170 2795);
DISPLAY INVISIBLE (-2170 2795);
FORCEADD DNS..2
(3230 3520);
PAINT RED (3230 3520);
FORCEPROP 2 LAST CDS_LIB mstr_misc
J 0
(3230 3520);
PAINT ORANGE (3230 3520);
DISPLAY INVISIBLE (3230 3520);
FORCEPROP 1 LAST COMMENT_BODY TRUE
R 1
J 0
(3305 3295);
DISPLAY 0.872340 (3305 3295);
PAINT GREEN (3305 3295);
DISPLAY INVISIBLE (3305 3295);
FORCEADD INTEL_CORP_BPAGE..1
(4700 200);
FORCEPROP 1 LAST CDS_CON_LAST_MODIFIED Fri Jun 16 17:48:33 2017
J 0
(3275 525);
PAINT ORANGE (3275 525);
DISPLAY INVISIBLE (3275 525);
FORCEPROP 1 LAST CUSTOM_TXT_CDS <CURRENT_DESIGN_SHEET> OF <TOTAL_DESIGN_SHEETS>
J 0
(4200 225);
PAINT ORANGE (4200 225);
FORCEPROP 1 LAST CUSTOM_TXT_CDS <CON_LAST_MODIFIED>
J 0
(700 300);
PAINT ORANGE (700 300);
FORCEPROP 2 LAST CUSTOM_TXT_CDS <XR_PAGE_TITLE>
J 0
(-3190 5450);
DISPLAY 0.638298 (-3190 5450);
PAINT PINK (-3190 5450);
DISPLAY INVISIBLE (-3190 5450);
FORCEPROP 1 LAST SCH_TITLE NVDIMM SUPPORT
J 0
(-3250 250);
DISPLAY 1.212766 (-3250 250);
PAINT ORANGE (-3250 250);
FORCEPROP 2 LAST PAGE_BORDER TRUE
J 0
(-3190 5450);
DISPLAY 0.638298 (-3190 5450);
PAINT PINK (-3190 5450);
DISPLAY INVISIBLE (-3190 5450);
FORCEPROP 2 LAST CDS_LIB mstr_symbols
J 0
(4700 200);
PAINT MONO (4700 200);
DISPLAY INVISIBLE (4700 200);
FORCEPROP 1 LAST COMMENT_BODY TRUE
J 0
(4712 212);
DISPLAY 0.468085 (4712 212);
PAINT GREEN (4712 212);
DISPLAY INVISIBLE (4712 212);
FORCEPROP 2 LAST CDS_XR_PAGE_TITLE CR-89 : @BASEBOARD_FAB2_LIB.BASEBOARD_FAB2(SCH_1):PAGE89
J 0
(-3190 5450);
DISPLAY 0.638298 (-3190 5450);
PAINT PINK (-3190 5450);
DISPLAY INVISIBLE (-3190 5450);
WIRE 16 -1 (-450 2625)(-450 2575);
WIRE 16 -1 (-450 3425)(-450 3525);
WIRE 16 -1 (1750 4600)(1750 4675);
WIRE 16 -1 (2450 4825)(2450 4900);
WIRE 16 -1 (2450 4075)(2450 4000);
WIRE 16 -1 (1750 3600)(1750 3525);
WIRE 16 -1 (-450 1450)(-450 1400);
WIRE 16 -1 (-450 2275)(-450 2375);
WIRE 16 -1 (2200 2400)(2200 2325);
WIRE 16 -1 (2950 2875)(2950 2800);
WIRE 16 -1 (2200 3350)(2200 3475);
WIRE 16 -1 (-125 3700)(675 3700);
FORCEPROP 2 LAST SIG_NAME IRQ_DIMM_SAVE_N
J 0
(115 3710);
DISPLAY 0.617021 (115 3710);
PAINT ORANGE (115 3710);
FORCEPROP 2 LASTPROP $XRERR UNIQUE?
J 0
(-125 3710);
DISPLAY 0.638298 (-125 3710);
PAINT MONO (-125 3710);
DISPLAY INVISIBLE (-125 3710);
WIRE 16 -1 (-450 2825)(-450 3125);
WIRE 16 -1 (-450 3125)(-450 3225);
WIRE 16 -1 (0 2825)(250 2825);
WIRE 16 -1 (-125 3125)(-450 3125);
WIRE 16 -1 (-125 3125)(-125 3700);
WIRE 16 -1 (-125 3125)(0 3125);
WIRE 16 -1 (0 2825)(0 3125);
WIRE 16 -1 (0 3125)(250 3125);
WIRE 16 -1 (1350 1650)(450 1650);
WIRE 3 682 (775 2725)(775 2225);
WIRE 3 682 (1850 2725)(775 2725);
WIRE 3 682 (775 2225)(1850 2225);
WIRE 3 682 (1850 2225)(1850 2725);
WIRE 16 -1 (450 1950)(1350 1950);
WIRE 16 -1 (100 2500)(900 2500);
WIRE 16 -1 (-450 1950)(-450 1650);
WIRE 16 -1 (-450 2075)(-450 1950);
WIRE 16 -1 (100 1950)(-450 1950);
FORCEPROP 2 LAST SIG_NAME FM_ADR_COMPLETE_CPU1_N
J 0
(-410 1960);
DISPLAY 0.638298 (-410 1960);
PAINT ORANGE (-410 1960);
FORCEPROP 2 LASTPROP $XRERR UNIQUE?
J 0
(-650 1960);
DISPLAY 0.638298 (-650 1960);
PAINT MONO (-650 1960);
DISPLAY INVISIBLE (-650 1960);
WIRE 16 -1 (100 1950)(250 1950);
WIRE 16 -1 (100 2500)(100 1950);
WIRE 16 -1 (100 1950)(100 1650);
WIRE 16 -1 (250 1650)(100 1650);
WIRE 16 -1 (450 3125)(1350 3125);
WIRE 3 682 (2025 3400)(2025 2200);
WIRE 3 682 (3300 3400)(2025 3400);
WIRE 3 682 (2025 2200)(3300 2200);
WIRE 3 682 (3300 2200)(3300 3400);
WIRE 16 -1 (-2825 2725)(-2350 2725);
WIRE 16 -1 (-2825 3025)(-2350 3025);
WIRE 16 -1 (1600 3700)(875 3700);
FORCEPROP 2 LAST SIG_NAME IRQ_DIMM_SAVE_R_N
J 0
(1015 3710);
DISPLAY 0.617021 (1015 3710);
PAINT ORANGE (1015 3710);
FORCEPROP 2 LASTPROP $XRERR UNIQUE?
J 0
(775 3710);
DISPLAY 0.638298 (775 3710);
PAINT MONO (775 3710);
DISPLAY INVISIBLE (775 3710);
WIRE 3 682 (1550 3400)(2000 3400);
WIRE 3 682 (1550 3900)(1550 3400);
WIRE 3 682 (2000 3400)(2000 3900);
WIRE 3 682 (2000 3900)(1550 3900);
WIRE 16 -1 (1100 2500)(2050 2500);
FORCEPROP 2 LAST SIG_NAME IRQ_DIMM_SAVE_CPU1_R_N
J 0
(1265 2510);
DISPLAY 0.617021 (1265 2510);
PAINT ORANGE (1265 2510);
FORCEPROP 2 LASTPROP $XRERR UNIQUE?
J 0
(1025 2510);
DISPLAY 0.638298 (1025 2510);
PAINT MONO (1025 2510);
DISPLAY INVISIBLE (1025 2510);
WIRE 16 -1 (3325 3525)(3850 3525);
FORCEPROP 2 LAST SIG_NAME FM_ADR_SMI_GPIO_N
J 2
(3825 3560);
DISPLAY 0.617021 (3825 3560);
PAINT ORANGE (3825 3560);
WIRE 16 -1 (2200 2600)(2200 2975);
FORCEPROP 2 LAST SIG_NAME IRQ_DIMM_SAVE_LVT3_CPU1
J 0
(2215 3010);
DISPLAY 0.617021 (2215 3010);
PAINT ORANGE (2215 3010);
FORCEPROP 2 LASTPROP $XRERR UNIQUE?
J 0
(1975 3010);
DISPLAY 0.638298 (1975 3010);
PAINT MONO (1975 3010);
DISPLAY INVISIBLE (1975 3010);
WIRE 16 -1 (2200 2975)(2200 3150);
WIRE 16 -1 (2800 2975)(2200 2975);
WIRE 3 682 (2150 3850)(2875 3850);
WIRE 3 682 (2150 4450)(2150 3850);
WIRE 3 682 (2875 3850)(2875 4450);
WIRE 3 682 (2875 4450)(2150 4450);
WIRE 16 -1 (2450 4275)(2450 4550);
WIRE 16 -1 (2450 4550)(2450 4625);
WIRE 16 -1 (2450 4550)(2950 4550);
FORCEPROP 2 LAST SIG_NAME IRQ_DIMM_SAVE_LVT3_N
J 0
(2765 4585);
DISPLAY 0.617021 (2765 4585);
PAINT ORANGE (2765 4585);
WIRE 16 -1 (2950 4550)(3450 4550);
WIRE 16 -1 (2950 3525)(3125 3525);
WIRE 16 -1 (2950 3525)(2950 4550);
WIRE 16 -1 (2950 3075)(2950 3525);
WIRE 16 -1 (1750 4175)(1750 4400);
WIRE 16 -1 (1750 4175)(2300 4175);
WIRE 16 -1 (1750 3800)(1750 4175);
FORCEPROP 2 LAST SIG_NAME IRQ_DIMM_SAVE_LVT3
J 0
(1765 4210);
DISPLAY 0.617021 (1765 4210);
PAINT ORANGE (1765 4210);
FORCEPROP 2 LASTPROP $XRERR UNIQUE?
J 0
(1525 4210);
DISPLAY 0.638298 (1525 4210);
PAINT MONO (1525 4210);
DISPLAY INVISIBLE (1525 4210);
WIRE 16 -1 (-1250 1550)(-600 1550);
FORCEPROP 2 LAST SIG_NAME FM_ADR_COMPLETE_CPU1_R
J 0
(-1185 1560);
DISPLAY 0.617021 (-1185 1560);
PAINT ORANGE (-1185 1560);
FORCEPROP 2 LASTPROP $XRERR UNIQUE?
J 0
(-1425 1560);
DISPLAY 0.638298 (-1425 1560);
PAINT MONO (-1425 1560);
DISPLAY INVISIBLE (-1425 1560);
WIRE 3 682 (-650 1300)(-650 2300);
WIRE 3 682 (150 1300)(-650 1300);
WIRE 3 682 (-650 2300)(150 2300);
WIRE 3 682 (150 2300)(150 1300);
WIRE 16 -1 (-2150 3025)(-1975 3025);
WIRE 16 -1 (-2150 2725)(-1975 2725);
FORCEPROP 2 LAST SIG_NAME FM_ADR_COMPLETE_R
J 0
(-1885 2735);
DISPLAY 0.617021 (-1885 2735);
PAINT ORANGE (-1885 2735);
FORCEPROP 2 LASTPROP $XRERR UNIQUE?
J 0
(-2125 2735);
DISPLAY 0.638298 (-2125 2735);
PAINT MONO (-2125 2735);
DISPLAY INVISIBLE (-2125 2735);
WIRE 16 -1 (-1975 3025)(-1975 2725);
WIRE 16 -1 (-1500 1550)(-1450 1550);
WIRE 16 -1 (-1500 2725)(-1500 1550);
WIRE 16 -1 (-1500 2725)(-1975 2725);
WIRE 16 -1 (-1450 2725)(-1500 2725);
WIRE 16 -1 (450 2825)(1350 2825);
WIRE 16 -1 (-1250 2725)(-600 2725);
FORCEPROP 2 LAST SIG_NAME FM_ADR_COMPLETE_CPU0_R
J 0
(-1210 2735);
DISPLAY 0.617021 (-1210 2735);
PAINT ORANGE (-1210 2735);
FORCEPROP 2 LASTPROP $XRERR UNIQUE?
J 0
(-1450 2735);
DISPLAY 0.638298 (-1450 2735);
PAINT MONO (-1450 2735);
DISPLAY INVISIBLE (-1450 2735);
WIRE 3 682 (-675 2950)(-675 2500);
WIRE 3 682 (-75 2950)(-675 2950);
WIRE 3 682 (-675 2500)(-75 2500);
WIRE 3 682 (-75 2500)(-75 2950);
WIRE 3 682 (-1350 2125)(-2350 2125);
WIRE 3 682 (-1350 1700)(-1350 2125);
WIRE 3 682 (-1350 2550)(-1350 2125);
DOT 1 (-1350 2125);
DOT 1 (-125 3125);
DOT 1 (-450 1950);
DOT 1 (-1500 2725);
DOT 1 (0 3125);
DOT 1 (-1975 2725);
DOT 1 (2450 4550);
DOT 1 (2950 4550);
DOT 1 (1750 4175);
DOT 1 (2950 3525);
DOT 1 (2200 2975);
DOT 1 (100 1950);
DOT 1 (-450 3125);
FORCENOTE
NVDIMM INTERNAL R-PULLUP TO VPP (2.5V) IS 2 K OHM TO SUPPORT UP TO 6 NVDIMM LOADS TOTAL ON ALL FM_ADR_COMPLETE_XXX_N NETS
(-2400 1200) 0;
DISPLAY LEFT (-2400 1200);
DISPLAY 1.021277 (-2400 1200);
PAINT PURPLE (-2400 1200);
FORCENOTE
TP FAB1 CHANGE Q8D1 BACK AS CRB 0406
(2350 3725) 0;
DISPLAY LEFT (2350 3725);
DISPLAY 1.021277 (2350 3725);
PAINT RED (2350 3725);
FORCENOTE
TP FAB1 CHANGE ADD BJT AND RES 0406
(2050 2150) 0;
DISPLAY LEFT (2050 2150);
DISPLAY 1.021277 (2050 2150);
PAINT RED (2050 2150);
FORCENOTE
ROOM=NVDIMM
(-3200 450) 0;
DISPLAY LEFT (-3200 450);
DISPLAY 1.021277 (-3200 450);
PAINT PURPLE (-3200 450);
FORCENOTE
BOM_COST=MEM_NV
(-3250 375) 0;
DISPLAY LEFT (-3250 375);
DISPLAY 1.021277 (-3250 375);
PAINT PURPLE (-3250 375);
FORCENOTE
TP FAB1 ADD MOS AND RES 0401
(175 1400) 0;
DISPLAY LEFT (175 1400);
DISPLAY 1.021277 (175 1400);
PAINT RED (175 1400);
FORCENOTE
TP FAB1 ADD DUAL RES 0405
(775 2175) 0;
DISPLAY LEFT (775 2175);
DISPLAY 1.021277 (775 2175);
PAINT RED (775 2175);
FORCENOTE
TP FAB1 CHANGE MOS TO BJT 0406
(175 1325) 0;
DISPLAY LEFT (175 1325);
DISPLAY 1.021277 (175 1325);
PAINT RED (175 1325);
FORCENOTE
TP FAB1 CHANGE MOS TO BJT 0406
(-50 2525) 0;
DISPLAY LEFT (-50 2525);
DISPLAY 0.638298 (-50 2525);
PAINT RED (-50 2525);
FORCENOTE
TP FAB1 ADD RES 0406
(-2350 2125) 0;
DISPLAY LEFT (-2350 2125);
DISPLAY 1.021277 (-2350 2125);
PAINT RED (-2350 2125);
FORCENOTE
TP FAB1 CHANGE TO SINGLE BJT 0405
(2350 3775) 0;
DISPLAY LEFT (2350 3775);
DISPLAY 1.021277 (2350 3775);
PAINT RED (2350 3775);
FORCENOTE
IMPORTANT DESIGN NOTE:
(-2400 1300) 0;
DISPLAY LEFT (-2400 1300);
DISPLAY 1.021277 (-2400 1300);
PAINT PURPLE (-2400 1300);
QUIT
